FILE_TYPE = MACRO_DRAWING;
SET COLOR_WIRE YELLOW;
SET COLOR_PROP ORANGE;
SET COLOR_DOT WHITE;
SET COLOR_ARC YELLOW;
SET COLOR_BODY GREEN;
SET COLOR_NOTE PURPLE;
SET PROP_DISPLAY VALUE;
SET PAGE_NUMBER P388;
FORCEADD Q_RES..2
R 2
(-4300 2775);
FORCEPROP 1 LAST LOCATION R961
J 2
(-4345 2900);
DISPLAY 0.978723 (-4345 2900);
FORCEPROP 0 LAST $SEC 1
J 0
(-4325 2950);
DISPLAY 0.680851 (-4325 2950);
PAINT MONO (-4325 2950);
DISPLAY INVISIBLE (-4325 2950);
FORCEPROP 0 LAST CDS_SEC 1
J 0
(-4325 2950);
DISPLAY 0.680851 (-4325 2950);
DISPLAY INVISIBLE (-4325 2950);
FORCEPROP 1 LASTPIN (-4300 2875) $PN 1
J 2
(-4305 2837);
DISPLAY 0.787234 (-4305 2837);
PAINT MONO (-4305 2837);
FORCEPROP 1 LASTPIN (-4300 2675) $PN 2
J 2
(-4305 2685);
DISPLAY 0.787234 (-4305 2685);
PAINT MONO (-4305 2685);
FORCEPROP 1 LAST MATERIAL EMPTY
J 2
(-4340 2700);
DISPLAY 0.978723 (-4340 2700);
FORCEPROP 1 LAST PACK_TYPE 0603LF
J 2
(-4340 2600);
DISPLAY 0.978723 (-4340 2600);
FORCEPROP 1 LAST WATTAGE 1/4W
J 2
(-4340 2750);
DISPLAY 0.978723 (-4340 2750);
FORCEPROP 1 LAST VALUE 0
J 2
(-4345 2850);
DISPLAY 0.978723 (-4345 2850);
FORCEPROP 1 LAST TOLERANCE 5%
J 2
(-4345 2800);
DISPLAY 0.978723 (-4345 2800);
FORCEPROP 2 LAST CDS_LIB pure_quanta
J 2
(-4300 2775);
DISPLAY INVISIBLE (-4300 2775);
FORCEPROP 1 LAST PATH I10
J 2
(-4350 2950);
DISPLAY 0.978723 (-4350 2950);
PAINT WHITE (-4350 2950);
DISPLAY INVISIBLE (-4350 2950);
FORCEPROP 1 LAST PART_NUMBER CS00006J900
J 2
(-4340 2650);
DISPLAY 0.978723 (-4340 2650);
DISPLAY INVISIBLE (-4340 2650);
FORCEADD Q_CAPP..1
(-750 2250);
FORCEPROP 1 LAST LOCATION C7009
J 0
(-700 2350);
DISPLAY 0.787234 (-700 2350);
FORCEPROP 0 LAST $SEC 1
J 0
(-700 2400);
DISPLAY 0.680851 (-700 2400);
PAINT MONO (-700 2400);
DISPLAY INVISIBLE (-700 2400);
FORCEPROP 0 LAST CDS_SEC 1
J 0
(-700 2400);
DISPLAY 0.680851 (-700 2400);
DISPLAY INVISIBLE (-700 2400);
FORCEPROP 1 LASTPIN (-750 2350) $PN 1
J 0
(-740 2335);
DISPLAY 0.787234 (-740 2335);
PAINT MONO (-740 2335);
FORCEPROP 1 LASTPIN (-750 2150) $PN 2
J 0
(-740 2135);
DISPLAY 0.787234 (-740 2135);
PAINT MONO (-740 2135);
FORCEPROP 1 LAST VALUE 470UF
J 0
(-700 2300);
DISPLAY 0.510638 (-700 2300);
FORCEPROP 1 LAST TOLERANCE 20%
J 0
(-700 2250);
DISPLAY 0.510638 (-700 2250);
FORCEPROP 1 LAST MATERIAL SPCAP
J 0
(-700 2150);
DISPLAY 0.510638 (-700 2150);
FORCEPROP 1 LAST PACK_TYPE SMLF
J 0
(-700 2100);
DISPLAY 0.510638 (-700 2100);
FORCEPROP 1 LAST VOLTAGE 2.5V
J 0
(-700 2200);
DISPLAY 0.510638 (-700 2200);
FORCEPROP 2 LAST CDS_LIB pure_quanta
J 0
(-750 2250);
DISPLAY INVISIBLE (-750 2250);
FORCEPROP 1 LAST PATH I100
J 0
(-700 2400);
DISPLAY 0.978723 (-700 2400);
DISPLAY INVISIBLE (-700 2400);
FORCEPROP 1 LAST PART_NUMBER CH747LM8818
J 0
(-700 2050);
DISPLAY 0.404255 (-700 2050);
DISPLAY INVISIBLE (-700 2050);
FORCEADD Q_CAP..1
(-475 2250);
FORCEPROP 1 LAST LOCATION C7010
J 0
(-425 2350);
DISPLAY 0.638298 (-425 2350);
FORCEPROP 0 LAST $SEC 1
J 0
(-425 2400);
DISPLAY 0.680851 (-425 2400);
PAINT MONO (-425 2400);
DISPLAY INVISIBLE (-425 2400);
FORCEPROP 0 LAST CDS_SEC 1
J 0
(-425 2400);
DISPLAY 0.680851 (-425 2400);
DISPLAY INVISIBLE (-425 2400);
FORCEPROP 1 LASTPIN (-475 2350) $PN 1
J 0
(-465 2330);
DISPLAY 0.787234 (-465 2330);
PAINT MONO (-465 2330);
FORCEPROP 1 LASTPIN (-475 2150) $PN 2
J 0
(-465 2130);
DISPLAY 0.787234 (-465 2130);
PAINT MONO (-465 2130);
FORCEPROP 1 LAST TOLERANCE 20%
J 0
(-425 2200);
DISPLAY 0.638298 (-425 2200);
FORCEPROP 1 LAST MATERIAL X6S
J 0
(-425 2150);
DISPLAY 0.638298 (-425 2150);
FORCEPROP 1 LAST PACK_TYPE C0805
J 0
(-425 2050);
DISPLAY 0.638298 (-425 2050);
FORCEPROP 1 LAST VALUE 100UF
J 0
(-425 2300);
DISPLAY 0.638298 (-425 2300);
FORCEPROP 1 LAST VOLTAGE 4V
J 0
(-425 2250);
DISPLAY 0.638298 (-425 2250);
FORCEPROP 2 LAST CDS_LIB pure_quanta
J 0
(-475 2250);
DISPLAY INVISIBLE (-475 2250);
FORCEPROP 1 LAST PATH I101
J 0
(-425 2400);
DISPLAY 0.978723 (-425 2400);
PAINT WHITE (-425 2400);
DISPLAY INVISIBLE (-425 2400);
FORCEPROP 1 LAST PART_NUMBER CH710KMEA01
J 0
(-425 2100);
DISPLAY 0.638298 (-425 2100);
DISPLAY INVISIBLE (-425 2100);
FORCEADD Q_CAPP..1
(-2000 4875);
FORCEPROP 1 LAST LOCATION C7032
J 0
(-1950 4975);
DISPLAY 0.638298 (-1950 4975);
FORCEPROP 0 LAST $SEC 1
J 0
(-1950 5025);
DISPLAY 0.680851 (-1950 5025);
PAINT MONO (-1950 5025);
DISPLAY INVISIBLE (-1950 5025);
FORCEPROP 0 LAST CDS_SEC 1
J 0
(-1950 5025);
DISPLAY 0.680851 (-1950 5025);
DISPLAY INVISIBLE (-1950 5025);
FORCEPROP 1 LASTPIN (-2000 4975) $PN 1
J 0
(-1990 4960);
DISPLAY 0.787234 (-1990 4960);
PAINT MONO (-1990 4960);
FORCEPROP 1 LASTPIN (-2000 4775) $PN 2
J 0
(-1990 4760);
DISPLAY 0.787234 (-1990 4760);
PAINT MONO (-1990 4760);
FORCEPROP 1 LAST PACK_TYPE SMLF
J 0
(-1950 4725);
DISPLAY 0.510638 (-1950 4725);
FORCEPROP 1 LAST MATERIAL SPCAP
J 0
(-1950 4775);
DISPLAY 0.510638 (-1950 4775);
FORCEPROP 1 LAST VOLTAGE 2.5V
J 0
(-1950 4825);
DISPLAY 0.510638 (-1950 4825);
FORCEPROP 1 LAST TOLERANCE 20%
J 0
(-1950 4875);
DISPLAY 0.510638 (-1950 4875);
FORCEPROP 1 LAST VALUE 470UF
J 0
(-1950 4925);
DISPLAY 0.510638 (-1950 4925);
FORCEPROP 2 LAST CDS_LIB pure_quanta
J 0
(-2000 4875);
DISPLAY INVISIBLE (-2000 4875);
FORCEPROP 1 LAST PATH I102
J 0
(-1950 5025);
DISPLAY 0.978723 (-1950 5025);
DISPLAY INVISIBLE (-1950 5025);
FORCEPROP 1 LAST PART_NUMBER CH747LM8818
J 0
(-1950 4675);
DISPLAY 0.404255 (-1950 4675);
DISPLAY INVISIBLE (-1950 4675);
FORCEADD Q_CAP..1
(-1650 4875);
FORCEPROP 1 LAST LOCATION C7033
J 0
(-1600 4975);
DISPLAY 0.638298 (-1600 4975);
FORCEPROP 0 LAST $SEC 1
J 0
(-1600 5025);
DISPLAY 0.680851 (-1600 5025);
PAINT MONO (-1600 5025);
DISPLAY INVISIBLE (-1600 5025);
FORCEPROP 0 LAST CDS_SEC 1
J 0
(-1600 5025);
DISPLAY 0.680851 (-1600 5025);
DISPLAY INVISIBLE (-1600 5025);
FORCEPROP 1 LASTPIN (-1650 4975) $PN 1
J 0
(-1640 4955);
DISPLAY 0.787234 (-1640 4955);
PAINT MONO (-1640 4955);
FORCEPROP 1 LASTPIN (-1650 4775) $PN 2
J 0
(-1640 4755);
DISPLAY 0.787234 (-1640 4755);
PAINT MONO (-1640 4755);
FORCEPROP 1 LAST MATERIAL X6S
J 0
(-1600 4775);
DISPLAY 0.638298 (-1600 4775);
FORCEPROP 1 LAST VALUE 47UF
J 0
(-1600 4925);
DISPLAY 0.638298 (-1600 4925);
FORCEPROP 1 LAST PACK_TYPE C0805
J 0
(-1600 4675);
DISPLAY 0.638298 (-1600 4675);
FORCEPROP 1 LAST VOLTAGE 4V
J 0
(-1600 4875);
DISPLAY 0.638298 (-1600 4875);
FORCEPROP 1 LAST TOLERANCE 20%
J 0
(-1600 4825);
DISPLAY 0.638298 (-1600 4825);
FORCEPROP 2 LAST CDS_LIB pure_quanta
J 0
(-1650 4875);
DISPLAY INVISIBLE (-1650 4875);
FORCEPROP 1 LAST PATH I103
J 0
(-1600 5025);
DISPLAY 0.978723 (-1600 5025);
PAINT WHITE (-1600 5025);
DISPLAY INVISIBLE (-1600 5025);
FORCEPROP 1 LAST PART_NUMBER CH647KMEA04
J 0
(-1600 4725);
DISPLAY 0.638298 (-1600 4725);
DISPLAY INVISIBLE (-1600 4725);
FORCEADD Q_CAP..1
(-1375 4875);
FORCEPROP 1 LAST LOCATION C7034
J 0
(-1325 4975);
DISPLAY 0.638298 (-1325 4975);
FORCEPROP 0 LAST $SEC 1
J 0
(-1325 5025);
DISPLAY 0.680851 (-1325 5025);
PAINT MONO (-1325 5025);
DISPLAY INVISIBLE (-1325 5025);
FORCEPROP 0 LAST CDS_SEC 1
J 0
(-1325 5025);
DISPLAY 0.680851 (-1325 5025);
DISPLAY INVISIBLE (-1325 5025);
FORCEPROP 1 LASTPIN (-1375 4975) $PN 1
J 0
(-1365 4955);
DISPLAY 0.787234 (-1365 4955);
PAINT MONO (-1365 4955);
FORCEPROP 1 LASTPIN (-1375 4775) $PN 2
J 0
(-1365 4755);
DISPLAY 0.787234 (-1365 4755);
PAINT MONO (-1365 4755);
FORCEPROP 1 LAST VALUE 47UF
J 0
(-1325 4925);
DISPLAY 0.638298 (-1325 4925);
FORCEPROP 1 LAST MATERIAL X6S
J 0
(-1325 4775);
DISPLAY 0.638298 (-1325 4775);
FORCEPROP 1 LAST PACK_TYPE C0805
J 0
(-1325 4675);
DISPLAY 0.638298 (-1325 4675);
FORCEPROP 1 LAST TOLERANCE 20%
J 0
(-1325 4825);
DISPLAY 0.638298 (-1325 4825);
FORCEPROP 1 LAST VOLTAGE 4V
J 0
(-1325 4875);
DISPLAY 0.638298 (-1325 4875);
FORCEPROP 2 LAST CDS_LIB pure_quanta
J 0
(-1375 4875);
DISPLAY INVISIBLE (-1375 4875);
FORCEPROP 1 LAST PATH I104
J 0
(-1325 5025);
DISPLAY 0.978723 (-1325 5025);
PAINT WHITE (-1325 5025);
DISPLAY INVISIBLE (-1325 5025);
FORCEPROP 1 LAST PART_NUMBER CH647KMEA04
J 0
(-1325 4725);
DISPLAY 0.638298 (-1325 4725);
DISPLAY INVISIBLE (-1325 4725);
FORCEADD Q_CAP..1
(-1125 4875);
FORCEPROP 1 LAST LOCATION C7035
J 0
(-1075 4975);
DISPLAY 0.638298 (-1075 4975);
FORCEPROP 0 LAST $SEC 1
J 0
(-1075 5025);
DISPLAY 0.680851 (-1075 5025);
PAINT MONO (-1075 5025);
DISPLAY INVISIBLE (-1075 5025);
FORCEPROP 0 LAST CDS_SEC 1
J 0
(-1075 5025);
DISPLAY 0.680851 (-1075 5025);
DISPLAY INVISIBLE (-1075 5025);
FORCEPROP 1 LASTPIN (-1125 4975) $PN 1
J 0
(-1115 4955);
DISPLAY 0.787234 (-1115 4955);
PAINT MONO (-1115 4955);
FORCEPROP 1 LASTPIN (-1125 4775) $PN 2
J 0
(-1115 4755);
DISPLAY 0.787234 (-1115 4755);
PAINT MONO (-1115 4755);
FORCEPROP 1 LAST VALUE 47UF
J 0
(-1075 4925);
DISPLAY 0.638298 (-1075 4925);
FORCEPROP 1 LAST VOLTAGE 4V
J 0
(-1075 4875);
DISPLAY 0.638298 (-1075 4875);
FORCEPROP 1 LAST PACK_TYPE C0805
J 0
(-1075 4675);
DISPLAY 0.638298 (-1075 4675);
FORCEPROP 1 LAST MATERIAL X6S
J 0
(-1075 4775);
DISPLAY 0.638298 (-1075 4775);
FORCEPROP 1 LAST TOLERANCE 20%
J 0
(-1075 4825);
DISPLAY 0.638298 (-1075 4825);
FORCEPROP 2 LAST CDS_LIB pure_quanta
J 0
(-1125 4875);
DISPLAY INVISIBLE (-1125 4875);
FORCEPROP 1 LAST PATH I105
J 0
(-1075 5025);
DISPLAY 0.978723 (-1075 5025);
PAINT WHITE (-1075 5025);
DISPLAY INVISIBLE (-1075 5025);
FORCEPROP 1 LAST PART_NUMBER CH647KMEA04
J 0
(-1075 4725);
DISPLAY 0.638298 (-1075 4725);
DISPLAY INVISIBLE (-1075 4725);
FORCEADD Q_CAP..1
(-850 4875);
FORCEPROP 1 LAST LOCATION C7036
J 0
(-800 4975);
DISPLAY 0.638298 (-800 4975);
FORCEPROP 0 LAST $SEC 1
J 0
(-800 5025);
DISPLAY 0.680851 (-800 5025);
PAINT MONO (-800 5025);
DISPLAY INVISIBLE (-800 5025);
FORCEPROP 0 LAST CDS_SEC 1
J 0
(-800 5025);
DISPLAY 0.680851 (-800 5025);
DISPLAY INVISIBLE (-800 5025);
FORCEPROP 1 LASTPIN (-850 4975) $PN 1
J 0
(-840 4955);
DISPLAY 0.787234 (-840 4955);
PAINT MONO (-840 4955);
FORCEPROP 1 LASTPIN (-850 4775) $PN 2
J 0
(-840 4755);
DISPLAY 0.787234 (-840 4755);
PAINT MONO (-840 4755);
FORCEPROP 1 LAST VOLTAGE 4V
J 0
(-800 4875);
DISPLAY 0.638298 (-800 4875);
FORCEPROP 1 LAST MATERIAL X6S
J 0
(-800 4775);
DISPLAY 0.638298 (-800 4775);
FORCEPROP 1 LAST VALUE 47UF
J 0
(-800 4925);
DISPLAY 0.638298 (-800 4925);
FORCEPROP 1 LAST TOLERANCE 20%
J 0
(-800 4825);
DISPLAY 0.638298 (-800 4825);
FORCEPROP 1 LAST PACK_TYPE C0805
J 0
(-800 4675);
DISPLAY 0.638298 (-800 4675);
FORCEPROP 2 LAST CDS_LIB pure_quanta
J 0
(-850 4875);
DISPLAY INVISIBLE (-850 4875);
FORCEPROP 1 LAST PATH I106
J 0
(-800 5025);
DISPLAY 0.978723 (-800 5025);
PAINT WHITE (-800 5025);
DISPLAY INVISIBLE (-800 5025);
FORCEPROP 1 LAST PART_NUMBER CH647KMEA04
J 0
(-800 4725);
DISPLAY 0.638298 (-800 4725);
DISPLAY INVISIBLE (-800 4725);
FORCEADD Q_RES..1
(-3925 2500);
FORCEPROP 1 LAST LOCATION R962
J 0
(-3975 2550);
DISPLAY 0.978723 (-3975 2550);
FORCEPROP 0 LAST $SEC 1
J 0
(-3975 2600);
DISPLAY 0.680851 (-3975 2600);
PAINT MONO (-3975 2600);
DISPLAY INVISIBLE (-3975 2600);
FORCEPROP 0 LAST CDS_SEC 1
J 0
(-3975 2600);
DISPLAY 0.680851 (-3975 2600);
DISPLAY INVISIBLE (-3975 2600);
FORCEPROP 1 LASTPIN (-4025 2500) $PN 1
J 0
(-4013 2512);
DISPLAY 0.787234 (-4013 2512);
PAINT MONO (-4013 2512);
FORCEPROP 1 LASTPIN (-3825 2500) $PN 2
J 0
(-3863 2512);
DISPLAY 0.787234 (-3863 2512);
PAINT MONO (-3863 2512);
FORCEPROP 1 LAST TOLERANCE 5%
J 0
(-3925 2400);
DISPLAY 0.978723 (-3925 2400);
FORCEPROP 1 LAST MATERIAL CHIP
J 0
(-3925 2350);
DISPLAY 0.978723 (-3925 2350);
FORCEPROP 1 LAST VALUE 0
J 2
(-3950 2400);
DISPLAY 0.978723 (-3950 2400);
FORCEPROP 1 LAST WATTAGE 1/4W
J 2
(-3950 2350);
DISPLAY 0.978723 (-3950 2350);
FORCEPROP 1 LAST PACK_TYPE 0603LF
J 0
(-3675 2350);
DISPLAY 0.978723 (-3675 2350);
FORCEPROP 2 LAST CDS_LIB pure_quanta
J 0
(-3925 2500);
DISPLAY INVISIBLE (-3925 2500);
FORCEPROP 1 LAST PATH I11
J 0
(-3975 2650);
DISPLAY 0.978723 (-3975 2650);
PAINT WHITE (-3975 2650);
DISPLAY INVISIBLE (-3975 2650);
FORCEPROP 1 LAST PART_NUMBER CS00006J900
J 0
(-4150 2275);
DISPLAY 0.978723 (-4150 2275);
DISPLAY INVISIBLE (-4150 2275);
FORCEADD Q_INDUCTOR..1
(-7775 4475);
FORCEPROP 1 LAST LOCATION L11
J 0
(-7900 4635);
DISPLAY 0.723404 (-7900 4635);
PAINT GREEN (-7900 4635);
FORCEPROP 0 LAST $SEC 1
J 0
(-7900 4725);
DISPLAY 0.680851 (-7900 4725);
PAINT MONO (-7900 4725);
DISPLAY INVISIBLE (-7900 4725);
FORCEPROP 0 LAST CDS_SEC 1
J 0
(-7900 4725);
DISPLAY 0.680851 (-7900 4725);
DISPLAY INVISIBLE (-7900 4725);
FORCEPROP 0 LASTPIN (-7875 4450) $PN 1
J 2
(-7885 4460);
DISPLAY 0.680851 (-7885 4460);
PAINT MONO (-7885 4460);
FORCEPROP 0 LASTPIN (-7675 4450) $PN 2
J 0
(-7665 4460);
DISPLAY 0.680851 (-7665 4460);
PAINT MONO (-7665 4460);
FORCEPROP 2 LAST PACK_TYPE SMLF
J 0
(-7900 4675);
DISPLAY 0.680851 (-7900 4675);
FORCEPROP 1 LAST MATERIAL IND
J 0
(-7900 4530);
DISPLAY 0.723404 (-7900 4530);
PAINT GREEN (-7900 4530);
FORCEPROP 2 LAST VALUE BLM21SN300SN1D/5A
J 0
(-8025 4375);
DISPLAY 0.680851 (-8025 4375);
FORCEPROP 2 LAST CDS_LIB pure_quanta
J 0
(-7775 4475);
DISPLAY INVISIBLE (-7775 4475);
FORCEPROP 1 LAST NEEDS_NO_SIZE TRUE
J 0
(-7775 4475);
DISPLAY 0.468085 (-7775 4475);
PAINT GREEN (-7775 4475);
DISPLAY INVISIBLE (-7775 4475);
FORCEPROP 1 LAST PATH I12
J 0
(-7700 4530);
DISPLAY 0.723404 (-7700 4530);
PAINT GREEN (-7700 4530);
DISPLAY INVISIBLE (-7700 4530);
FORCEPROP 1 LAST PART_NUMBER CX300SN1000
J 0
(-7900 4585);
DISPLAY 0.723404 (-7900 4585);
PAINT GREEN (-7900 4585);
DISPLAY INVISIBLE (-7900 4585);
FORCEADD Q_CAP..1
(-7200 4200);
FORCEPROP 1 LAST LOCATION C503
J 0
(-7150 4300);
DISPLAY 0.638298 (-7150 4300);
PAINT WHITE (-7150 4300);
FORCEPROP 0 LAST $SEC 1
J 0
(-7150 4325);
DISPLAY 0.680851 (-7150 4325);
PAINT MONO (-7150 4325);
DISPLAY INVISIBLE (-7150 4325);
FORCEPROP 0 LAST CDS_SEC 1
J 0
(-7150 4325);
DISPLAY 0.680851 (-7150 4325);
DISPLAY INVISIBLE (-7150 4325);
FORCEPROP 1 LASTPIN (-7200 4300) $PN 1
J 0
(-7190 4280);
DISPLAY 0.787234 (-7190 4280);
PAINT MONO (-7190 4280);
FORCEPROP 1 LASTPIN (-7200 4100) $PN 2
J 0
(-7190 4080);
DISPLAY 0.787234 (-7190 4080);
PAINT MONO (-7190 4080);
FORCEPROP 1 LAST VALUE 100UF
J 0
(-7150 4250);
DISPLAY 0.510638 (-7150 4250);
FORCEPROP 1 LAST PACK_TYPE C0805
J 0
(-7150 4050);
DISPLAY 0.510638 (-7150 4050);
FORCEPROP 1 LAST VOLTAGE 4V
J 0
(-7150 4200);
DISPLAY 0.510638 (-7150 4200);
FORCEPROP 1 LAST MATERIAL X6S
J 0
(-7150 4100);
DISPLAY 0.510638 (-7150 4100);
FORCEPROP 1 LAST TOLERANCE 20%
J 0
(-7150 4150);
DISPLAY 0.510638 (-7150 4150);
FORCEPROP 2 LAST CDS_LIB pure_quanta
J 0
(-7200 4200);
DISPLAY INVISIBLE (-7200 4200);
FORCEPROP 1 LAST PATH I13
J 0
(-7150 4350);
DISPLAY 0.978723 (-7150 4350);
PAINT WHITE (-7150 4350);
DISPLAY INVISIBLE (-7150 4350);
FORCEPROP 1 LAST PART_NUMBER CH710KMEA01
J 0
(-7150 4050);
DISPLAY 0.404255 (-7150 4050);
DISPLAY INVISIBLE (-7150 4050);
FORCEADD Q_CAP..1
(-6975 4200);
FORCEPROP 1 LAST LOCATION C505
J 0
(-6925 4300);
DISPLAY 0.638298 (-6925 4300);
PAINT WHITE (-6925 4300);
FORCEPROP 0 LAST $SEC 1
J 0
(-6925 4325);
DISPLAY 0.680851 (-6925 4325);
PAINT MONO (-6925 4325);
DISPLAY INVISIBLE (-6925 4325);
FORCEPROP 0 LAST CDS_SEC 1
J 0
(-6925 4325);
DISPLAY 0.680851 (-6925 4325);
DISPLAY INVISIBLE (-6925 4325);
FORCEPROP 1 LASTPIN (-6975 4300) $PN 1
J 0
(-6965 4280);
DISPLAY 0.787234 (-6965 4280);
PAINT MONO (-6965 4280);
FORCEPROP 1 LASTPIN (-6975 4100) $PN 2
J 0
(-6965 4080);
DISPLAY 0.787234 (-6965 4080);
PAINT MONO (-6965 4080);
FORCEPROP 1 LAST TOLERANCE 20%
J 0
(-6925 4150);
DISPLAY 0.510638 (-6925 4150);
FORCEPROP 1 LAST PACK_TYPE C0402
J 0
(-6925 4050);
DISPLAY 0.510638 (-6925 4050);
FORCEPROP 1 LAST VALUE 22UF
J 0
(-6925 4250);
DISPLAY 0.510638 (-6925 4250);
FORCEPROP 1 LAST MATERIAL X6S
J 0
(-6925 4100);
DISPLAY 0.510638 (-6925 4100);
FORCEPROP 1 LAST VOLTAGE 4V
J 0
(-6925 4200);
DISPLAY 0.510638 (-6925 4200);
FORCEPROP 2 LAST CDS_LIB pure_quanta
J 0
(-6975 4200);
DISPLAY INVISIBLE (-6975 4200);
FORCEPROP 1 LAST PATH I14
J 0
(-6925 4350);
DISPLAY 0.978723 (-6925 4350);
PAINT WHITE (-6925 4350);
DISPLAY INVISIBLE (-6925 4350);
FORCEPROP 1 LAST PART_NUMBER CH622KMEB02
J 0
(-6925 4050);
DISPLAY 0.978723 (-6925 4050);
DISPLAY INVISIBLE (-6925 4050);
FORCEADD P1V0..1
(-7300 4675);
FORCEPROP 3 LASTPIN (-7300 4625) SIG_NAME P1V8_CPU0_RT0_1A\g
J 0
(-7290 4635);
DISPLAY 0.659574 (-7290 4635);
PAINT MONO (-7290 4635);
DISPLAY INVISIBLE (-7290 4635);
FORCEPROP 1 LAST HDL_POWER P1V8_CPU0_RT0_1A
J 1
(-7300 4725);
DISPLAY 0.489362 (-7300 4725);
PAINT SKYBLUE (-7300 4725);
FORCEPROP 2 LAST CDS_LIB pure_quanta_power
J 0
(-7300 4675);
DISPLAY INVISIBLE (-7300 4675);
FORCEPROP 1 LAST PATH I15
J 0
(-7250 4700);
DISPLAY 0.872340 (-7250 4700);
PAINT AQUA (-7250 4700);
DISPLAY INVISIBLE (-7250 4700);
FORCEADD Q_CAP..1
(-7050 5025);
FORCEPROP 1 LAST LOCATION C502
J 0
(-7000 5125);
DISPLAY 0.638298 (-7000 5125);
PAINT WHITE (-7000 5125);
FORCEPROP 0 LAST $SEC 1
J 0
(-7000 5175);
DISPLAY 0.680851 (-7000 5175);
PAINT MONO (-7000 5175);
DISPLAY INVISIBLE (-7000 5175);
FORCEPROP 0 LAST CDS_SEC 1
J 0
(-7000 5175);
DISPLAY 0.680851 (-7000 5175);
DISPLAY INVISIBLE (-7000 5175);
FORCEPROP 1 LASTPIN (-7050 5125) $PN 1
J 0
(-7040 5105);
DISPLAY 0.787234 (-7040 5105);
PAINT MONO (-7040 5105);
FORCEPROP 1 LASTPIN (-7050 4925) $PN 2
J 0
(-7040 4905);
DISPLAY 0.787234 (-7040 4905);
PAINT MONO (-7040 4905);
FORCEPROP 1 LAST VOLTAGE 4V
J 0
(-7000 5025);
DISPLAY 0.510638 (-7000 5025);
FORCEPROP 1 LAST PACK_TYPE C0805
J 0
(-7000 4875);
DISPLAY 0.510638 (-7000 4875);
FORCEPROP 1 LAST VALUE 100UF
J 0
(-7000 5075);
DISPLAY 0.510638 (-7000 5075);
FORCEPROP 1 LAST TOLERANCE 20%
J 0
(-7000 4975);
DISPLAY 0.510638 (-7000 4975);
FORCEPROP 1 LAST MATERIAL X6S
J 0
(-7000 4925);
DISPLAY 0.510638 (-7000 4925);
FORCEPROP 2 LAST CDS_LIB pure_quanta
J 0
(-7050 5025);
DISPLAY INVISIBLE (-7050 5025);
FORCEPROP 1 LAST PATH I16
J 0
(-7000 5175);
DISPLAY 0.978723 (-7000 5175);
PAINT WHITE (-7000 5175);
DISPLAY INVISIBLE (-7000 5175);
FORCEPROP 1 LAST PART_NUMBER CH710KMEA01
J 0
(-7000 4875);
DISPLAY 0.404255 (-7000 4875);
DISPLAY INVISIBLE (-7000 4875);
FORCEADD Q_CAP..1
(-6775 4200);
FORCEPROP 1 LAST LOCATION C507
J 0
(-6725 4300);
DISPLAY 0.808511 (-6725 4300);
PAINT WHITE (-6725 4300);
FORCEPROP 0 LAST $SEC 1
J 0
(-6725 4350);
DISPLAY 0.680851 (-6725 4350);
PAINT MONO (-6725 4350);
DISPLAY INVISIBLE (-6725 4350);
FORCEPROP 0 LAST CDS_SEC 1
J 0
(-6725 4350);
DISPLAY 0.680851 (-6725 4350);
DISPLAY INVISIBLE (-6725 4350);
FORCEPROP 1 LASTPIN (-6775 4300) $PN 1
J 0
(-6765 4280);
DISPLAY 0.787234 (-6765 4280);
PAINT MONO (-6765 4280);
FORCEPROP 1 LASTPIN (-6775 4100) $PN 2
J 0
(-6765 4080);
DISPLAY 0.787234 (-6765 4080);
PAINT MONO (-6765 4080);
FORCEPROP 1 LAST VOLTAGE 6.3V
J 0
(-6725 4200);
DISPLAY 0.510638 (-6725 4200);
FORCEPROP 1 LAST VALUE 10UF
J 0
(-6725 4250);
DISPLAY 0.510638 (-6725 4250);
FORCEPROP 1 LAST MATERIAL X6S
J 0
(-6725 4100);
DISPLAY 0.510638 (-6725 4100);
FORCEPROP 1 LAST PACK_TYPE C0402
J 0
(-6725 4050);
DISPLAY 0.510638 (-6725 4050);
FORCEPROP 1 LAST TOLERANCE 20%
J 0
(-6725 4150);
DISPLAY 0.510638 (-6725 4150);
FORCEPROP 2 LAST CDS_LIB pure_quanta
J 0
(-6775 4200);
DISPLAY INVISIBLE (-6775 4200);
FORCEPROP 1 LAST PATH I17
J 0
(-6725 4350);
DISPLAY 0.978723 (-6725 4350);
PAINT WHITE (-6725 4350);
DISPLAY INVISIBLE (-6725 4350);
FORCEPROP 1 LAST PART_NUMBER CH6101MEB01
J 0
(-6725 4050);
DISPLAY 0.978723 (-6725 4050);
DISPLAY INVISIBLE (-6725 4050);
FORCEADD Q_CAP..1
(-6575 4200);
FORCEPROP 1 LAST LOCATION C510
J 0
(-6525 4300);
DISPLAY 0.638298 (-6525 4300);
PAINT WHITE (-6525 4300);
FORCEPROP 0 LAST $SEC 1
J 0
(-6525 4325);
DISPLAY 0.680851 (-6525 4325);
PAINT MONO (-6525 4325);
DISPLAY INVISIBLE (-6525 4325);
FORCEPROP 0 LAST CDS_SEC 1
J 0
(-6525 4325);
DISPLAY 0.680851 (-6525 4325);
DISPLAY INVISIBLE (-6525 4325);
FORCEPROP 1 LASTPIN (-6575 4300) $PN 1
J 0
(-6565 4280);
DISPLAY 0.787234 (-6565 4280);
PAINT MONO (-6565 4280);
FORCEPROP 1 LASTPIN (-6575 4100) $PN 2
J 0
(-6565 4080);
DISPLAY 0.787234 (-6565 4080);
PAINT MONO (-6565 4080);
FORCEPROP 1 LAST PACK_TYPE 0402
J 0
(-6525 4050);
DISPLAY 0.510638 (-6525 4050);
FORCEPROP 1 LAST MATERIAL X6S
J 0
(-6525 4100);
DISPLAY 0.510638 (-6525 4100);
FORCEPROP 1 LAST VOLTAGE 6.3V
J 0
(-6525 4200);
DISPLAY 0.510638 (-6525 4200);
FORCEPROP 1 LAST VALUE 4.7UF
J 0
(-6525 4250);
DISPLAY 0.510638 (-6525 4250);
FORCEPROP 1 LAST TOLERANCE 20%
J 0
(-6525 4150);
DISPLAY 0.510638 (-6525 4150);
FORCEPROP 2 LAST CDS_LIB pure_quanta
J 0
(-6575 4200);
DISPLAY INVISIBLE (-6575 4200);
FORCEPROP 1 LAST PATH I18
J 0
(-6525 4350);
DISPLAY 0.978723 (-6525 4350);
PAINT WHITE (-6525 4350);
DISPLAY INVISIBLE (-6525 4350);
FORCEPROP 1 LAST PART_NUMBER CH5471MEB01
J 0
(-6525 4050);
DISPLAY 0.978723 (-6525 4050);
DISPLAY INVISIBLE (-6525 4050);
FORCEADD Q_CAP..1
(-6350 4200);
FORCEPROP 1 LAST LOCATION C512
J 0
(-6300 4300);
DISPLAY 0.808511 (-6300 4300);
PAINT WHITE (-6300 4300);
FORCEPROP 0 LAST $SEC 1
J 0
(-6300 4350);
DISPLAY 0.680851 (-6300 4350);
PAINT MONO (-6300 4350);
DISPLAY INVISIBLE (-6300 4350);
FORCEPROP 0 LAST CDS_SEC 1
J 0
(-6300 4350);
DISPLAY 0.680851 (-6300 4350);
DISPLAY INVISIBLE (-6300 4350);
FORCEPROP 1 LASTPIN (-6350 4300) $PN 1
J 0
(-6340 4280);
DISPLAY 0.787234 (-6340 4280);
PAINT MONO (-6340 4280);
FORCEPROP 1 LASTPIN (-6350 4100) $PN 2
J 0
(-6340 4080);
DISPLAY 0.787234 (-6340 4080);
PAINT MONO (-6340 4080);
FORCEPROP 1 LAST PACK_TYPE 0201
J 0
(-6300 4050);
DISPLAY 0.510638 (-6300 4050);
FORCEPROP 1 LAST MATERIAL X6S
J 0
(-6300 4100);
DISPLAY 0.510638 (-6300 4100);
FORCEPROP 1 LAST VOLTAGE 4V
J 0
(-6300 4200);
DISPLAY 0.510638 (-6300 4200);
FORCEPROP 1 LAST VALUE 1UF
J 0
(-6300 4250);
DISPLAY 0.510638 (-6300 4250);
FORCEPROP 1 LAST TOLERANCE 20%
J 0
(-6300 4150);
DISPLAY 0.510638 (-6300 4150);
FORCEPROP 2 LAST CDS_LIB pure_quanta
J 0
(-6350 4200);
DISPLAY INVISIBLE (-6350 4200);
FORCEPROP 1 LAST PATH I19
J 0
(-6300 4350);
DISPLAY 0.978723 (-6300 4350);
PAINT WHITE (-6300 4350);
DISPLAY INVISIBLE (-6300 4350);
FORCEPROP 1 LAST PART_NUMBER CH-10KMEE00
J 0
(-6300 4050);
DISPLAY 0.510638 (-6300 4050);
DISPLAY INVISIBLE (-6300 4050);
FORCEADD UNIVERSAL_GND..1
(-6375 4725);
FORCEPROP 3 LASTPIN (-6375 4775) SIG_NAME GND\g
J 0
(-6365 4785);
DISPLAY 0.659574 (-6365 4785);
PAINT MONO (-6365 4785);
DISPLAY INVISIBLE (-6365 4785);
FORCEPROP 2 LAST CDS_LIB pure_quanta_power
J 0
(-6375 4725);
DISPLAY INVISIBLE (-6375 4725);
FORCEPROP 1 LAST HDL_POWER GND
J 1
(-6350 4650);
DISPLAY 0.872340 (-6350 4650);
PAINT GREEN (-6350 4650);
DISPLAY INVISIBLE (-6350 4650);
FORCEPROP 1 LAST PATH I20
J 0
(-6300 4725);
DISPLAY 0.872340 (-6300 4725);
PAINT AQUA (-6300 4725);
DISPLAY INVISIBLE (-6300 4725);
FORCEADD UNIVERSAL_GND..1
(-6150 3875);
FORCEPROP 3 LASTPIN (-6150 3925) SIG_NAME GND\g
J 0
(-6140 3935);
DISPLAY 0.659574 (-6140 3935);
PAINT MONO (-6140 3935);
DISPLAY INVISIBLE (-6140 3935);
FORCEPROP 2 LAST CDS_LIB pure_quanta_power
J 0
(-6150 3875);
DISPLAY INVISIBLE (-6150 3875);
FORCEPROP 1 LAST HDL_POWER GND
J 1
(-6125 3800);
DISPLAY 0.872340 (-6125 3800);
PAINT GREEN (-6125 3800);
DISPLAY INVISIBLE (-6125 3800);
FORCEPROP 1 LAST PATH I21
J 0
(-6075 3875);
DISPLAY 0.872340 (-6075 3875);
PAINT AQUA (-6075 3875);
DISPLAY INVISIBLE (-6075 3875);
FORCEADD Q_CAP..1
(-6150 4200);
FORCEPROP 1 LAST LOCATION C514
J 0
(-6100 4300);
DISPLAY 0.808511 (-6100 4300);
PAINT WHITE (-6100 4300);
FORCEPROP 0 LAST $SEC 1
J 0
(-6100 4350);
DISPLAY 0.680851 (-6100 4350);
PAINT MONO (-6100 4350);
DISPLAY INVISIBLE (-6100 4350);
FORCEPROP 0 LAST CDS_SEC 1
J 0
(-6100 4350);
DISPLAY 0.680851 (-6100 4350);
DISPLAY INVISIBLE (-6100 4350);
FORCEPROP 1 LASTPIN (-6150 4300) $PN 1
J 0
(-6140 4280);
DISPLAY 0.787234 (-6140 4280);
PAINT MONO (-6140 4280);
FORCEPROP 1 LASTPIN (-6150 4100) $PN 2
J 0
(-6140 4080);
DISPLAY 0.787234 (-6140 4080);
PAINT MONO (-6140 4080);
FORCEPROP 1 LAST MATERIAL X6S
J 0
(-6100 4100);
DISPLAY 0.510638 (-6100 4100);
FORCEPROP 1 LAST VOLTAGE 4V
J 0
(-6100 4200);
DISPLAY 0.510638 (-6100 4200);
FORCEPROP 1 LAST VALUE 1UF
J 0
(-6100 4250);
DISPLAY 0.510638 (-6100 4250);
FORCEPROP 1 LAST PACK_TYPE 0201
J 0
(-6100 4050);
DISPLAY 0.510638 (-6100 4050);
FORCEPROP 1 LAST TOLERANCE 20%
J 0
(-6100 4150);
DISPLAY 0.510638 (-6100 4150);
FORCEPROP 2 LAST CDS_LIB pure_quanta
J 0
(-6150 4200);
DISPLAY INVISIBLE (-6150 4200);
FORCEPROP 1 LAST PATH I22
J 0
(-6100 4350);
DISPLAY 0.978723 (-6100 4350);
PAINT WHITE (-6100 4350);
DISPLAY INVISIBLE (-6100 4350);
FORCEPROP 1 LAST PART_NUMBER CH-10KMEE00
J 0
(-6100 4050);
DISPLAY 0.510638 (-6100 4050);
DISPLAY INVISIBLE (-6100 4050);
FORCEADD Q_CAP..1
(-5925 4200);
FORCEPROP 1 LAST LOCATION C515
J 0
(-5875 4300);
DISPLAY 0.978723 (-5875 4300);
PAINT WHITE (-5875 4300);
FORCEPROP 0 LAST $SEC 1
J 0
(-5875 4350);
DISPLAY 0.680851 (-5875 4350);
PAINT MONO (-5875 4350);
DISPLAY INVISIBLE (-5875 4350);
FORCEPROP 0 LAST CDS_SEC 1
J 0
(-5875 4350);
DISPLAY 0.680851 (-5875 4350);
DISPLAY INVISIBLE (-5875 4350);
FORCEPROP 1 LASTPIN (-5925 4300) $PN 1
J 0
(-5915 4280);
DISPLAY 0.787234 (-5915 4280);
PAINT MONO (-5915 4280);
FORCEPROP 1 LASTPIN (-5925 4100) $PN 2
J 0
(-5915 4080);
DISPLAY 0.787234 (-5915 4080);
PAINT MONO (-5915 4080);
FORCEPROP 1 LAST TOLERANCE 10%
J 0
(-5875 4150);
DISPLAY 0.638298 (-5875 4150);
FORCEPROP 1 LAST VOLTAGE 10V
J 0
(-5875 4200);
DISPLAY 0.638298 (-5875 4200);
FORCEPROP 1 LAST VALUE 0.1UF
J 0
(-5875 4250);
DISPLAY 0.638298 (-5875 4250);
FORCEPROP 1 LAST PACK_TYPE C0201
J 0
(-5875 4050);
DISPLAY 0.638298 (-5875 4050);
FORCEPROP 1 LAST MATERIAL X7S
J 0
(-5875 4100);
DISPLAY 0.638298 (-5875 4100);
FORCEPROP 2 LAST CDS_LIB pure_quanta
J 0
(-5925 4200);
DISPLAY INVISIBLE (-5925 4200);
FORCEPROP 1 LAST PATH I23
J 0
(-5875 4350);
DISPLAY 0.978723 (-5875 4350);
PAINT WHITE (-5875 4350);
DISPLAY INVISIBLE (-5875 4350);
FORCEPROP 1 LAST PART_NUMBER CH4102K6E00
J 0
(-5875 4050);
DISPLAY 0.978723 (-5875 4050);
DISPLAY INVISIBLE (-5875 4050);
FORCEADD Q_CAP..1
(-6800 5025);
FORCEPROP 1 LAST LOCATION C504
J 0
(-6750 5125);
DISPLAY 0.510638 (-6750 5125);
PAINT WHITE (-6750 5125);
FORCEPROP 0 LAST $SEC 1
J 0
(-6750 5150);
DISPLAY 0.680851 (-6750 5150);
PAINT MONO (-6750 5150);
DISPLAY INVISIBLE (-6750 5150);
FORCEPROP 0 LAST CDS_SEC 1
J 0
(-6750 5150);
DISPLAY 0.680851 (-6750 5150);
DISPLAY INVISIBLE (-6750 5150);
FORCEPROP 1 LASTPIN (-6800 5125) $PN 1
J 0
(-6790 5105);
DISPLAY 0.787234 (-6790 5105);
PAINT MONO (-6790 5105);
FORCEPROP 1 LASTPIN (-6800 4925) $PN 2
J 0
(-6790 4905);
DISPLAY 0.787234 (-6790 4905);
PAINT MONO (-6790 4905);
FORCEPROP 1 LAST TOLERANCE 20%
J 0
(-6750 4975);
DISPLAY 0.510638 (-6750 4975);
FORCEPROP 1 LAST MATERIAL X6S
J 0
(-6750 4925);
DISPLAY 0.510638 (-6750 4925);
FORCEPROP 1 LAST VOLTAGE 4V
J 0
(-6750 5025);
DISPLAY 0.510638 (-6750 5025);
FORCEPROP 1 LAST VALUE 22UF
J 0
(-6750 5075);
DISPLAY 0.510638 (-6750 5075);
FORCEPROP 1 LAST PACK_TYPE C0402
J 0
(-6750 4875);
DISPLAY 0.510638 (-6750 4875);
FORCEPROP 2 LAST CDS_LIB pure_quanta
J 0
(-6800 5025);
DISPLAY INVISIBLE (-6800 5025);
FORCEPROP 1 LAST PATH I24
J 0
(-6750 5175);
DISPLAY 0.978723 (-6750 5175);
PAINT WHITE (-6750 5175);
DISPLAY INVISIBLE (-6750 5175);
FORCEPROP 1 LAST PART_NUMBER CH622KMEB02
J 0
(-6750 4875);
DISPLAY 0.978723 (-6750 4875);
DISPLAY INVISIBLE (-6750 4875);
FORCEADD Q_CAP..1
(-6550 5000);
FORCEPROP 1 LAST LOCATION C506
J 0
(-6500 5100);
DISPLAY 0.638298 (-6500 5100);
PAINT WHITE (-6500 5100);
FORCEPROP 0 LAST $SEC 1
J 0
(-6500 5150);
DISPLAY 0.680851 (-6500 5150);
PAINT MONO (-6500 5150);
DISPLAY INVISIBLE (-6500 5150);
FORCEPROP 0 LAST CDS_SEC 1
J 0
(-6500 5150);
DISPLAY 0.680851 (-6500 5150);
DISPLAY INVISIBLE (-6500 5150);
FORCEPROP 1 LASTPIN (-6550 5100) $PN 1
J 0
(-6540 5080);
DISPLAY 0.787234 (-6540 5080);
PAINT MONO (-6540 5080);
FORCEPROP 1 LASTPIN (-6550 4900) $PN 2
J 0
(-6540 4880);
DISPLAY 0.787234 (-6540 4880);
PAINT MONO (-6540 4880);
FORCEPROP 1 LAST PACK_TYPE C0402
J 0
(-6500 4850);
DISPLAY 0.510638 (-6500 4850);
FORCEPROP 1 LAST TOLERANCE 20%
J 0
(-6500 4950);
DISPLAY 0.510638 (-6500 4950);
FORCEPROP 1 LAST VOLTAGE 6.3V
J 0
(-6500 5000);
DISPLAY 0.510638 (-6500 5000);
FORCEPROP 1 LAST VALUE 10UF
J 0
(-6500 5050);
DISPLAY 0.510638 (-6500 5050);
FORCEPROP 1 LAST MATERIAL X6S
J 0
(-6500 4900);
DISPLAY 0.510638 (-6500 4900);
FORCEPROP 2 LAST CDS_LIB pure_quanta
J 0
(-6550 5000);
DISPLAY INVISIBLE (-6550 5000);
FORCEPROP 1 LAST PATH I25
J 0
(-6500 5150);
DISPLAY 0.978723 (-6500 5150);
PAINT WHITE (-6500 5150);
DISPLAY INVISIBLE (-6500 5150);
FORCEPROP 1 LAST PART_NUMBER CH6101MEB01
J 0
(-6500 4850);
DISPLAY 0.978723 (-6500 4850);
DISPLAY INVISIBLE (-6500 4850);
FORCEADD Q_CAP..1
(-6300 5000);
FORCEPROP 1 LAST LOCATION C511
J 0
(-6250 5100);
DISPLAY 0.638298 (-6250 5100);
PAINT WHITE (-6250 5100);
FORCEPROP 0 LAST $SEC 1
J 0
(-6250 5150);
DISPLAY 0.680851 (-6250 5150);
PAINT MONO (-6250 5150);
DISPLAY INVISIBLE (-6250 5150);
FORCEPROP 0 LAST CDS_SEC 1
J 0
(-6250 5150);
DISPLAY 0.680851 (-6250 5150);
DISPLAY INVISIBLE (-6250 5150);
FORCEPROP 1 LASTPIN (-6300 5100) $PN 1
J 0
(-6290 5080);
DISPLAY 0.787234 (-6290 5080);
PAINT MONO (-6290 5080);
FORCEPROP 1 LASTPIN (-6300 4900) $PN 2
J 0
(-6290 4880);
DISPLAY 0.787234 (-6290 4880);
PAINT MONO (-6290 4880);
FORCEPROP 1 LAST PACK_TYPE 0402
J 0
(-6250 4850);
DISPLAY 0.510638 (-6250 4850);
FORCEPROP 1 LAST VALUE 4.7UF
J 0
(-6250 5050);
DISPLAY 0.510638 (-6250 5050);
FORCEPROP 1 LAST MATERIAL X6S
J 0
(-6250 4900);
DISPLAY 0.510638 (-6250 4900);
FORCEPROP 1 LAST VOLTAGE 6.3V
J 0
(-6250 5000);
DISPLAY 0.510638 (-6250 5000);
FORCEPROP 1 LAST TOLERANCE 20%
J 0
(-6250 4950);
DISPLAY 0.510638 (-6250 4950);
FORCEPROP 2 LAST CDS_LIB pure_quanta
J 0
(-6300 5000);
DISPLAY INVISIBLE (-6300 5000);
FORCEPROP 1 LAST PATH I26
J 0
(-6250 5150);
DISPLAY 0.978723 (-6250 5150);
PAINT WHITE (-6250 5150);
DISPLAY INVISIBLE (-6250 5150);
FORCEPROP 1 LAST PART_NUMBER CH5471MEB01
J 0
(-6250 4850);
DISPLAY 0.978723 (-6250 4850);
DISPLAY INVISIBLE (-6250 4850);
FORCEADD Q_CAP..1
(-5675 4200);
FORCEPROP 1 LAST LOCATION C517
J 0
(-5625 4300);
DISPLAY 0.978723 (-5625 4300);
PAINT WHITE (-5625 4300);
FORCEPROP 0 LAST $SEC 1
J 0
(-5625 4350);
DISPLAY 0.680851 (-5625 4350);
PAINT MONO (-5625 4350);
DISPLAY INVISIBLE (-5625 4350);
FORCEPROP 0 LAST CDS_SEC 1
J 0
(-5625 4350);
DISPLAY 0.680851 (-5625 4350);
DISPLAY INVISIBLE (-5625 4350);
FORCEPROP 1 LASTPIN (-5675 4300) $PN 1
J 0
(-5665 4280);
DISPLAY 0.787234 (-5665 4280);
PAINT MONO (-5665 4280);
FORCEPROP 1 LASTPIN (-5675 4100) $PN 2
J 0
(-5665 4080);
DISPLAY 0.787234 (-5665 4080);
PAINT MONO (-5665 4080);
FORCEPROP 1 LAST VALUE 0.1UF
J 0
(-5625 4250);
DISPLAY 0.638298 (-5625 4250);
FORCEPROP 1 LAST VOLTAGE 10V
J 0
(-5625 4200);
DISPLAY 0.638298 (-5625 4200);
FORCEPROP 1 LAST MATERIAL X7S
J 0
(-5625 4100);
DISPLAY 0.638298 (-5625 4100);
FORCEPROP 1 LAST PACK_TYPE C0201
J 0
(-5625 4050);
DISPLAY 0.638298 (-5625 4050);
FORCEPROP 1 LAST TOLERANCE 10%
J 0
(-5625 4150);
DISPLAY 0.638298 (-5625 4150);
FORCEPROP 2 LAST CDS_LIB pure_quanta
J 0
(-5675 4200);
DISPLAY INVISIBLE (-5675 4200);
FORCEPROP 1 LAST PATH I27
J 0
(-5625 4350);
DISPLAY 0.978723 (-5625 4350);
PAINT WHITE (-5625 4350);
DISPLAY INVISIBLE (-5625 4350);
FORCEPROP 1 LAST PART_NUMBER CH4102K6E00
J 0
(-5625 4050);
DISPLAY 0.978723 (-5625 4050);
DISPLAY INVISIBLE (-5625 4050);
FORCEADD Q_CAP..1
(-5425 4200);
FORCEPROP 1 LAST LOCATION C519
J 0
(-5375 4300);
DISPLAY 0.978723 (-5375 4300);
PAINT WHITE (-5375 4300);
FORCEPROP 0 LAST $SEC 1
J 0
(-5375 4350);
DISPLAY 0.680851 (-5375 4350);
PAINT MONO (-5375 4350);
DISPLAY INVISIBLE (-5375 4350);
FORCEPROP 0 LAST CDS_SEC 1
J 0
(-5375 4350);
DISPLAY 0.680851 (-5375 4350);
DISPLAY INVISIBLE (-5375 4350);
FORCEPROP 1 LASTPIN (-5425 4300) $PN 1
J 0
(-5415 4280);
DISPLAY 0.787234 (-5415 4280);
PAINT MONO (-5415 4280);
FORCEPROP 1 LASTPIN (-5425 4100) $PN 2
J 0
(-5415 4080);
DISPLAY 0.787234 (-5415 4080);
PAINT MONO (-5415 4080);
FORCEPROP 1 LAST VALUE 0.1UF
J 0
(-5375 4250);
DISPLAY 0.638298 (-5375 4250);
FORCEPROP 1 LAST VOLTAGE 10V
J 0
(-5375 4200);
DISPLAY 0.638298 (-5375 4200);
FORCEPROP 1 LAST TOLERANCE 10%
J 0
(-5375 4150);
DISPLAY 0.638298 (-5375 4150);
FORCEPROP 1 LAST PACK_TYPE C0201
J 0
(-5375 4050);
DISPLAY 0.638298 (-5375 4050);
FORCEPROP 1 LAST MATERIAL X7S
J 0
(-5375 4100);
DISPLAY 0.638298 (-5375 4100);
FORCEPROP 2 LAST CDS_LIB pure_quanta
J 0
(-5425 4200);
DISPLAY INVISIBLE (-5425 4200);
FORCEPROP 1 LAST PATH I28
J 0
(-5375 4350);
DISPLAY 0.978723 (-5375 4350);
PAINT WHITE (-5375 4350);
DISPLAY INVISIBLE (-5375 4350);
FORCEPROP 1 LAST PART_NUMBER CH4102K6E00
J 0
(-5375 4050);
DISPLAY 0.978723 (-5375 4050);
DISPLAY INVISIBLE (-5375 4050);
FORCEADD Q_CAP..1
(-5150 4200);
FORCEPROP 1 LAST LOCATION C520
J 0
(-5100 4300);
DISPLAY 0.978723 (-5100 4300);
PAINT WHITE (-5100 4300);
FORCEPROP 0 LAST $SEC 1
J 0
(-5100 4350);
DISPLAY 0.680851 (-5100 4350);
PAINT MONO (-5100 4350);
DISPLAY INVISIBLE (-5100 4350);
FORCEPROP 0 LAST CDS_SEC 1
J 0
(-5100 4350);
DISPLAY 0.680851 (-5100 4350);
DISPLAY INVISIBLE (-5100 4350);
FORCEPROP 1 LASTPIN (-5150 4300) $PN 1
J 0
(-5140 4280);
DISPLAY 0.787234 (-5140 4280);
PAINT MONO (-5140 4280);
FORCEPROP 1 LASTPIN (-5150 4100) $PN 2
J 0
(-5140 4080);
DISPLAY 0.787234 (-5140 4080);
PAINT MONO (-5140 4080);
FORCEPROP 1 LAST VALUE 0.1UF
J 0
(-5100 4250);
DISPLAY 0.638298 (-5100 4250);
FORCEPROP 1 LAST MATERIAL X7S
J 0
(-5100 4100);
DISPLAY 0.638298 (-5100 4100);
FORCEPROP 1 LAST TOLERANCE 10%
J 0
(-5100 4150);
DISPLAY 0.638298 (-5100 4150);
FORCEPROP 1 LAST PACK_TYPE C0201
J 0
(-5100 4050);
DISPLAY 0.638298 (-5100 4050);
FORCEPROP 1 LAST VOLTAGE 10V
J 0
(-5100 4200);
DISPLAY 0.638298 (-5100 4200);
FORCEPROP 2 LAST CDS_LIB pure_quanta
J 0
(-5150 4200);
DISPLAY INVISIBLE (-5150 4200);
FORCEPROP 1 LAST PATH I29
J 0
(-5100 4350);
DISPLAY 0.978723 (-5100 4350);
PAINT WHITE (-5100 4350);
DISPLAY INVISIBLE (-5100 4350);
FORCEPROP 1 LAST PART_NUMBER CH4102K6E00
J 0
(-5100 4050);
DISPLAY 0.978723 (-5100 4050);
DISPLAY INVISIBLE (-5100 4050);
FORCEADD P1V0..1
(-8150 5300);
FORCEPROP 3 LASTPIN (-8150 5250) SIG_NAME P1V8_CPU0_RT_1D\g
J 0
(-8140 5260);
DISPLAY 0.659574 (-8140 5260);
PAINT MONO (-8140 5260);
DISPLAY INVISIBLE (-8140 5260);
FORCEPROP 1 LAST HDL_POWER P1V8_CPU0_RT_1D
J 1
(-8150 5350);
DISPLAY 0.489362 (-8150 5350);
PAINT SKYBLUE (-8150 5350);
FORCEPROP 2 LAST CDS_LIB pure_quanta_power
J 0
(-8150 5300);
DISPLAY INVISIBLE (-8150 5300);
FORCEPROP 1 LAST PATH I3
J 0
(-8100 5325);
DISPLAY 0.872340 (-8100 5325);
PAINT AQUA (-8100 5325);
DISPLAY INVISIBLE (-8100 5325);
FORCEADD Q_INDUCTOR..1
(-3825 4475);
FORCEPROP 1 LAST LOCATION L12
J 0
(-3950 4635);
DISPLAY 0.723404 (-3950 4635);
PAINT GREEN (-3950 4635);
FORCEPROP 0 LAST $SEC 1
J 0
(-3950 4775);
DISPLAY 0.680851 (-3950 4775);
PAINT MONO (-3950 4775);
DISPLAY INVISIBLE (-3950 4775);
FORCEPROP 0 LAST CDS_SEC 1
J 0
(-3950 4775);
DISPLAY 0.680851 (-3950 4775);
DISPLAY INVISIBLE (-3950 4775);
FORCEPROP 0 LASTPIN (-3925 4450) $PN 1
J 2
(-3935 4460);
DISPLAY 0.680851 (-3935 4460);
PAINT MONO (-3935 4460);
FORCEPROP 0 LASTPIN (-3725 4450) $PN 2
J 0
(-3715 4460);
DISPLAY 0.680851 (-3715 4460);
PAINT MONO (-3715 4460);
FORCEPROP 2 LAST PACK_TYPE SMLF
J 0
(-3950 4675);
DISPLAY 0.680851 (-3950 4675);
FORCEPROP 2 LAST VALUE 100NH/16A
J 0
(-3950 4725);
DISPLAY 0.680851 (-3950 4725);
FORCEPROP 1 LAST MATERIAL IND
J 0
(-3950 4530);
DISPLAY 0.723404 (-3950 4530);
PAINT GREEN (-3950 4530);
FORCEPROP 1 LAST NEEDS_NO_SIZE TRUE
J 0
(-3825 4475);
DISPLAY 0.468085 (-3825 4475);
PAINT GREEN (-3825 4475);
DISPLAY INVISIBLE (-3825 4475);
FORCEPROP 2 LAST CDS_LIB pure_quanta
J 0
(-3825 4475);
DISPLAY INVISIBLE (-3825 4475);
FORCEPROP 1 LAST PATH I30
J 0
(-3750 4530);
DISPLAY 0.723404 (-3750 4530);
PAINT GREEN (-3750 4530);
DISPLAY INVISIBLE (-3750 4530);
FORCEPROP 1 LAST PART_NUMBER CV+10G0MZ04
J 0
(-3950 4585);
DISPLAY 0.723404 (-3950 4585);
PAINT GREEN (-3950 4585);
DISPLAY INVISIBLE (-3950 4585);
FORCEADD VCC_CORE..1
(-4300 5975);
FORCEPROP 3 LASTPIN (-4300 5925) SIG_NAME P0V9_CPU0_RT_2D\g
J 0
(-4290 5935);
DISPLAY 0.659574 (-4290 5935);
PAINT MONO (-4290 5935);
DISPLAY INVISIBLE (-4290 5935);
FORCEPROP 1 LAST HDL_POWER P0V9_CPU0_RT_2D
J 1
(-4300 6025);
DISPLAY 0.617021 (-4300 6025);
PAINT GREEN (-4300 6025);
FORCEPROP 2 LAST CDS_LIB pure_quanta_power
J 0
(-4300 5975);
DISPLAY INVISIBLE (-4300 5975);
FORCEPROP 1 LAST PATH I31
J 0
(-4250 6000);
DISPLAY 0.872340 (-4250 6000);
PAINT AQUA (-4250 6000);
DISPLAY INVISIBLE (-4250 6000);
FORCEADD Q_CAP..1
(-3025 1150);
FORCEPROP 1 LAST LOCATION C538
J 0
(-2975 1250);
DISPLAY 0.978723 (-2975 1250);
PAINT WHITE (-2975 1250);
FORCEPROP 0 LAST $SEC 1
J 0
(-2975 1300);
DISPLAY 0.680851 (-2975 1300);
PAINT MONO (-2975 1300);
DISPLAY INVISIBLE (-2975 1300);
FORCEPROP 0 LAST CDS_SEC 1
J 0
(-2975 1300);
DISPLAY 0.680851 (-2975 1300);
DISPLAY INVISIBLE (-2975 1300);
FORCEPROP 1 LASTPIN (-3025 1250) $PN 1
J 0
(-3015 1230);
DISPLAY 0.787234 (-3015 1230);
PAINT MONO (-3015 1230);
FORCEPROP 1 LASTPIN (-3025 1050) $PN 2
J 0
(-3015 1030);
DISPLAY 0.787234 (-3015 1030);
PAINT MONO (-3015 1030);
FORCEPROP 1 LAST MATERIAL X7S
J 0
(-2975 1050);
DISPLAY 0.638298 (-2975 1050);
FORCEPROP 1 LAST PACK_TYPE C0201
J 0
(-2975 1000);
DISPLAY 0.638298 (-2975 1000);
FORCEPROP 1 LAST TOLERANCE 10%
J 0
(-2975 1100);
DISPLAY 0.638298 (-2975 1100);
FORCEPROP 1 LAST VOLTAGE 10V
J 0
(-2975 1150);
DISPLAY 0.638298 (-2975 1150);
FORCEPROP 1 LAST VALUE 0.1UF
J 0
(-2975 1200);
DISPLAY 0.638298 (-2975 1200);
FORCEPROP 2 LAST CDS_LIB pure_quanta
J 0
(-3025 1150);
DISPLAY INVISIBLE (-3025 1150);
FORCEPROP 1 LAST PATH I32
J 0
(-2975 1300);
DISPLAY 0.978723 (-2975 1300);
PAINT WHITE (-2975 1300);
DISPLAY INVISIBLE (-2975 1300);
FORCEPROP 1 LAST PART_NUMBER CH4102K6E00
J 0
(-2975 1000);
DISPLAY 0.978723 (-2975 1000);
DISPLAY INVISIBLE (-2975 1000);
FORCEADD VCC_CORE..1
(-3150 1675);
FORCEPROP 3 LASTPIN (-3150 1625) SIG_NAME P0V9_CPU0_RT0_2A_2D\g
J 0
(-3140 1635);
DISPLAY 0.659574 (-3140 1635);
PAINT MONO (-3140 1635);
DISPLAY INVISIBLE (-3140 1635);
FORCEPROP 1 LAST HDL_POWER P0V9_CPU0_RT0_2A_2D
J 1
(-3150 1725);
DISPLAY 0.617021 (-3150 1725);
PAINT GREEN (-3150 1725);
FORCEPROP 2 LAST CDS_LIB pure_quanta_power
J 0
(-3150 1675);
DISPLAY INVISIBLE (-3150 1675);
FORCEPROP 1 LAST PATH I33
J 0
(-3100 1700);
DISPLAY 0.872340 (-3100 1700);
PAINT AQUA (-3100 1700);
DISPLAY INVISIBLE (-3100 1700);
FORCEADD UNIVERSAL_GND..1
(-2325 825);
FORCEPROP 3 LASTPIN (-2325 875) SIG_NAME GND\g
J 0
(-2315 885);
DISPLAY 0.659574 (-2315 885);
PAINT MONO (-2315 885);
DISPLAY INVISIBLE (-2315 885);
FORCEPROP 2 LAST CDS_LIB pure_quanta_power
J 0
(-2325 825);
DISPLAY INVISIBLE (-2325 825);
FORCEPROP 1 LAST HDL_POWER GND
J 1
(-2300 750);
DISPLAY 0.872340 (-2300 750);
PAINT GREEN (-2300 750);
DISPLAY INVISIBLE (-2300 750);
FORCEPROP 1 LAST PATH I35
J 0
(-2250 825);
DISPLAY 0.872340 (-2250 825);
PAINT AQUA (-2250 825);
DISPLAY INVISIBLE (-2250 825);
FORCEADD Q_CAP..1
(-2475 1150);
FORCEPROP 1 LAST LOCATION C544
J 0
(-2425 1250);
DISPLAY 0.978723 (-2425 1250);
PAINT WHITE (-2425 1250);
FORCEPROP 0 LAST $SEC 1
J 0
(-2425 1300);
DISPLAY 0.680851 (-2425 1300);
PAINT MONO (-2425 1300);
DISPLAY INVISIBLE (-2425 1300);
FORCEPROP 0 LAST CDS_SEC 1
J 0
(-2425 1300);
DISPLAY 0.680851 (-2425 1300);
DISPLAY INVISIBLE (-2425 1300);
FORCEPROP 1 LASTPIN (-2475 1250) $PN 1
J 0
(-2465 1230);
DISPLAY 0.787234 (-2465 1230);
PAINT MONO (-2465 1230);
FORCEPROP 1 LASTPIN (-2475 1050) $PN 2
J 0
(-2465 1030);
DISPLAY 0.787234 (-2465 1030);
PAINT MONO (-2465 1030);
FORCEPROP 1 LAST TOLERANCE 10%
J 0
(-2425 1100);
DISPLAY 0.638298 (-2425 1100);
FORCEPROP 1 LAST PACK_TYPE C0201
J 0
(-2425 1000);
DISPLAY 0.638298 (-2425 1000);
FORCEPROP 1 LAST MATERIAL X7S
J 0
(-2425 1050);
DISPLAY 0.638298 (-2425 1050);
FORCEPROP 1 LAST VOLTAGE 10V
J 0
(-2425 1150);
DISPLAY 0.638298 (-2425 1150);
FORCEPROP 1 LAST VALUE 0.1UF
J 0
(-2425 1200);
DISPLAY 0.638298 (-2425 1200);
FORCEPROP 2 LAST CDS_LIB pure_quanta
J 0
(-2475 1150);
DISPLAY INVISIBLE (-2475 1150);
FORCEPROP 1 LAST PATH I36
J 0
(-2425 1300);
DISPLAY 0.978723 (-2425 1300);
PAINT WHITE (-2425 1300);
DISPLAY INVISIBLE (-2425 1300);
FORCEPROP 1 LAST PART_NUMBER CH4102K6E00
J 0
(-2425 1000);
DISPLAY 0.978723 (-2425 1000);
DISPLAY INVISIBLE (-2425 1000);
FORCEADD Q_CAP..1
(-3200 2250);
FORCEPROP 1 LAST LOCATION C576
J 0
(-3150 2350);
DISPLAY 0.978723 (-3150 2350);
PAINT WHITE (-3150 2350);
FORCEPROP 0 LAST $SEC 1
J 0
(-3150 2400);
DISPLAY 0.680851 (-3150 2400);
PAINT MONO (-3150 2400);
DISPLAY INVISIBLE (-3150 2400);
FORCEPROP 0 LAST CDS_SEC 1
J 0
(-3150 2400);
DISPLAY 0.680851 (-3150 2400);
DISPLAY INVISIBLE (-3150 2400);
FORCEPROP 1 LASTPIN (-3200 2350) $PN 1
J 0
(-3190 2330);
DISPLAY 0.787234 (-3190 2330);
PAINT MONO (-3190 2330);
FORCEPROP 1 LASTPIN (-3200 2150) $PN 2
J 0
(-3190 2130);
DISPLAY 0.787234 (-3190 2130);
PAINT MONO (-3190 2130);
FORCEPROP 1 LAST VOLTAGE 10V
J 0
(-3150 2250);
DISPLAY 0.638298 (-3150 2250);
FORCEPROP 1 LAST PACK_TYPE C0201
J 0
(-3150 2100);
DISPLAY 0.638298 (-3150 2100);
FORCEPROP 1 LAST MATERIAL X7S
J 0
(-3150 2150);
DISPLAY 0.638298 (-3150 2150);
FORCEPROP 1 LAST TOLERANCE 10%
J 0
(-3150 2200);
DISPLAY 0.638298 (-3150 2200);
FORCEPROP 1 LAST VALUE 0.1UF
J 0
(-3150 2300);
DISPLAY 0.638298 (-3150 2300);
FORCEPROP 2 LAST CDS_LIB pure_quanta
J 0
(-3200 2250);
DISPLAY INVISIBLE (-3200 2250);
FORCEPROP 1 LAST PATH I38
J 0
(-3150 2400);
DISPLAY 0.978723 (-3150 2400);
PAINT WHITE (-3150 2400);
DISPLAY INVISIBLE (-3150 2400);
FORCEPROP 1 LAST PART_NUMBER CH4102K6E00
J 0
(-3150 2100);
DISPLAY 0.978723 (-3150 2100);
DISPLAY INVISIBLE (-3150 2100);
FORCEADD Q_CAP..1
(-2900 2250);
FORCEPROP 1 LAST LOCATION C580
J 0
(-2850 2350);
DISPLAY 0.978723 (-2850 2350);
PAINT WHITE (-2850 2350);
FORCEPROP 0 LAST $SEC 1
J 0
(-2850 2400);
DISPLAY 0.680851 (-2850 2400);
PAINT MONO (-2850 2400);
DISPLAY INVISIBLE (-2850 2400);
FORCEPROP 0 LAST CDS_SEC 1
J 0
(-2850 2400);
DISPLAY 0.680851 (-2850 2400);
DISPLAY INVISIBLE (-2850 2400);
FORCEPROP 1 LASTPIN (-2900 2350) $PN 1
J 0
(-2890 2330);
DISPLAY 0.787234 (-2890 2330);
PAINT MONO (-2890 2330);
FORCEPROP 1 LASTPIN (-2900 2150) $PN 2
J 0
(-2890 2130);
DISPLAY 0.787234 (-2890 2130);
PAINT MONO (-2890 2130);
FORCEPROP 1 LAST VALUE 0.1UF
J 0
(-2850 2300);
DISPLAY 0.638298 (-2850 2300);
FORCEPROP 1 LAST VOLTAGE 10V
J 0
(-2850 2250);
DISPLAY 0.638298 (-2850 2250);
FORCEPROP 1 LAST TOLERANCE 10%
J 0
(-2850 2200);
DISPLAY 0.638298 (-2850 2200);
FORCEPROP 1 LAST MATERIAL X7S
J 0
(-2850 2150);
DISPLAY 0.638298 (-2850 2150);
FORCEPROP 1 LAST PACK_TYPE C0201
J 0
(-2850 2100);
DISPLAY 0.638298 (-2850 2100);
FORCEPROP 2 LAST CDS_LIB pure_quanta
J 0
(-2900 2250);
DISPLAY INVISIBLE (-2900 2250);
FORCEPROP 1 LAST PATH I39
J 0
(-2850 2400);
DISPLAY 0.978723 (-2850 2400);
PAINT WHITE (-2850 2400);
DISPLAY INVISIBLE (-2850 2400);
FORCEPROP 1 LAST PART_NUMBER CH4102K6E00
J 0
(-2850 2100);
DISPLAY 0.978723 (-2850 2100);
DISPLAY INVISIBLE (-2850 2100);
FORCEADD Q_RES..1
(-7700 3575);
FORCEPROP 1 LAST LOCATION R952
J 0
(-7975 3575);
DISPLAY 0.787234 (-7975 3575);
FORCEPROP 2 LAST SEC 1
J 0
(-7750 3775);
DISPLAY 0.680851 (-7750 3775);
PAINT MONO (-7750 3775);
DISPLAY INVISIBLE (-7750 3775);
FORCEPROP 1 LASTPIN (-7800 3575) $PN 1
J 0
(-7788 3587);
DISPLAY 0.787234 (-7788 3587);
PAINT MONO (-7788 3587);
FORCEPROP 1 LASTPIN (-7600 3575) $PN 2
J 0
(-7638 3587);
DISPLAY 0.787234 (-7638 3587);
PAINT MONO (-7638 3587);
FORCEPROP 1 LAST VALUE 0
J 2
(-7550 3600);
DISPLAY 0.638298 (-7550 3600);
FORCEPROP 1 LAST MATERIAL EMPTY
J 0
(-7675 3475);
DISPLAY 0.638298 (-7675 3475);
PAINT RED (-7675 3475);
FORCEPROP 1 LAST PACK_TYPE 0402LF
J 0
(-7850 3525);
DISPLAY 0.638298 (-7850 3525);
FORCEPROP 1 LAST TOLERANCE 5%
J 0
(-7650 3525);
DISPLAY 0.638298 (-7650 3525);
FORCEPROP 1 LAST WATTAGE 1/16W
J 2
(-7700 3475);
DISPLAY 0.638298 (-7700 3475);
FORCEPROP 2 LAST CDS_LIB pure_quanta
J 0
(-7700 3575);
DISPLAY INVISIBLE (-7700 3575);
FORCEPROP 2 LAST SEC_TYPE 0402LF
J 0
(-7750 3775);
DISPLAY 0.680851 (-7750 3775);
DISPLAY INVISIBLE (-7750 3775);
FORCEPROP 1 LAST PATH I4
J 0
(-7750 3725);
DISPLAY 0.978723 (-7750 3725);
PAINT WHITE (-7750 3725);
DISPLAY INVISIBLE (-7750 3725);
FORCEPROP 1 LAST PART_NUMBER CS00002JB13
J 0
(-7750 3675);
DISPLAY 0.978723 (-7750 3675);
DISPLAY INVISIBLE (-7750 3675);
FORCEADD Q_CAP..1
(-3475 2950);
FORCEPROP 1 LAST LOCATION C555
J 0
(-3425 3050);
DISPLAY 0.978723 (-3425 3050);
PAINT WHITE (-3425 3050);
FORCEPROP 0 LAST $SEC 1
J 0
(-3425 3100);
DISPLAY 0.680851 (-3425 3100);
PAINT MONO (-3425 3100);
DISPLAY INVISIBLE (-3425 3100);
FORCEPROP 0 LAST CDS_SEC 1
J 0
(-3425 3100);
DISPLAY 0.680851 (-3425 3100);
DISPLAY INVISIBLE (-3425 3100);
FORCEPROP 1 LASTPIN (-3475 3050) $PN 1
J 0
(-3465 3030);
DISPLAY 0.787234 (-3465 3030);
PAINT MONO (-3465 3030);
FORCEPROP 1 LASTPIN (-3475 2850) $PN 2
J 0
(-3465 2830);
DISPLAY 0.787234 (-3465 2830);
PAINT MONO (-3465 2830);
FORCEPROP 1 LAST MATERIAL X6S
J 0
(-3425 2850);
DISPLAY 0.510638 (-3425 2850);
FORCEPROP 1 LAST VALUE 1UF
J 0
(-3425 3000);
DISPLAY 0.510638 (-3425 3000);
FORCEPROP 1 LAST PACK_TYPE 0201
J 0
(-3425 2800);
DISPLAY 0.510638 (-3425 2800);
FORCEPROP 1 LAST VOLTAGE 4V
J 0
(-3425 2950);
DISPLAY 0.510638 (-3425 2950);
FORCEPROP 1 LAST TOLERANCE 20%
J 0
(-3425 2900);
DISPLAY 0.510638 (-3425 2900);
FORCEPROP 2 LAST CDS_LIB pure_quanta
J 0
(-3475 2950);
DISPLAY INVISIBLE (-3475 2950);
FORCEPROP 1 LAST PATH I40
J 0
(-3425 3100);
DISPLAY 0.978723 (-3425 3100);
PAINT WHITE (-3425 3100);
DISPLAY INVISIBLE (-3425 3100);
FORCEPROP 1 LAST PART_NUMBER CH-10KMEE00
J 0
(-3425 2800);
DISPLAY 0.510638 (-3425 2800);
DISPLAY INVISIBLE (-3425 2800);
FORCEADD Q_CAP..1
(-3475 3575);
FORCEPROP 1 LAST LOCATION C561
J 0
(-3425 3675);
DISPLAY 0.978723 (-3425 3675);
PAINT WHITE (-3425 3675);
FORCEPROP 0 LAST $SEC 1
J 0
(-3425 3725);
DISPLAY 0.680851 (-3425 3725);
PAINT MONO (-3425 3725);
DISPLAY INVISIBLE (-3425 3725);
FORCEPROP 0 LAST CDS_SEC 1
J 0
(-3425 3725);
DISPLAY 0.680851 (-3425 3725);
DISPLAY INVISIBLE (-3425 3725);
FORCEPROP 1 LASTPIN (-3475 3675) $PN 1
J 0
(-3465 3655);
DISPLAY 0.787234 (-3465 3655);
PAINT MONO (-3465 3655);
FORCEPROP 1 LASTPIN (-3475 3475) $PN 2
J 0
(-3465 3455);
DISPLAY 0.787234 (-3465 3455);
PAINT MONO (-3465 3455);
FORCEPROP 1 LAST PACK_TYPE C0402
J 0
(-3425 3425);
DISPLAY 0.510638 (-3425 3425);
FORCEPROP 1 LAST MATERIAL X6S
J 0
(-3425 3475);
DISPLAY 0.510638 (-3425 3475);
FORCEPROP 1 LAST TOLERANCE 20%
J 0
(-3425 3525);
DISPLAY 0.510638 (-3425 3525);
FORCEPROP 1 LAST VOLTAGE 6.3V
J 0
(-3425 3575);
DISPLAY 0.510638 (-3425 3575);
FORCEPROP 1 LAST VALUE 10UF
J 0
(-3425 3625);
DISPLAY 0.510638 (-3425 3625);
FORCEPROP 2 LAST CDS_LIB pure_quanta
J 0
(-3475 3575);
DISPLAY INVISIBLE (-3475 3575);
FORCEPROP 1 LAST PATH I41
J 0
(-3425 3725);
DISPLAY 0.978723 (-3425 3725);
PAINT WHITE (-3425 3725);
DISPLAY INVISIBLE (-3425 3725);
FORCEPROP 1 LAST PART_NUMBER CH6101MEB01
J 0
(-3425 3425);
DISPLAY 0.978723 (-3425 3425);
DISPLAY INVISIBLE (-3425 3425);
FORCEADD Q_CAP..1
(-3250 2950);
FORCEPROP 1 LAST LOCATION C539
J 0
(-3200 3050);
DISPLAY 0.978723 (-3200 3050);
PAINT WHITE (-3200 3050);
FORCEPROP 0 LAST $SEC 1
J 0
(-3200 3100);
DISPLAY 0.680851 (-3200 3100);
PAINT MONO (-3200 3100);
DISPLAY INVISIBLE (-3200 3100);
FORCEPROP 0 LAST CDS_SEC 1
J 0
(-3200 3100);
DISPLAY 0.680851 (-3200 3100);
DISPLAY INVISIBLE (-3200 3100);
FORCEPROP 1 LASTPIN (-3250 3050) $PN 1
J 0
(-3240 3030);
DISPLAY 0.787234 (-3240 3030);
PAINT MONO (-3240 3030);
FORCEPROP 1 LASTPIN (-3250 2850) $PN 2
J 0
(-3240 2830);
DISPLAY 0.787234 (-3240 2830);
PAINT MONO (-3240 2830);
FORCEPROP 1 LAST MATERIAL X6S
J 0
(-3200 2850);
DISPLAY 0.510638 (-3200 2850);
FORCEPROP 1 LAST VALUE 1UF
J 0
(-3200 3000);
DISPLAY 0.510638 (-3200 3000);
FORCEPROP 1 LAST VOLTAGE 4V
J 0
(-3200 2950);
DISPLAY 0.510638 (-3200 2950);
FORCEPROP 1 LAST TOLERANCE 20%
J 0
(-3200 2900);
DISPLAY 0.510638 (-3200 2900);
FORCEPROP 1 LAST PACK_TYPE 0201
J 0
(-3200 2800);
DISPLAY 0.510638 (-3200 2800);
FORCEPROP 2 LAST CDS_LIB pure_quanta
J 0
(-3250 2950);
DISPLAY INVISIBLE (-3250 2950);
FORCEPROP 1 LAST PATH I42
J 0
(-3200 3100);
DISPLAY 0.978723 (-3200 3100);
PAINT WHITE (-3200 3100);
DISPLAY INVISIBLE (-3200 3100);
FORCEPROP 1 LAST PART_NUMBER CH-10KMEE00
J 0
(-3200 2800);
DISPLAY 0.510638 (-3200 2800);
DISPLAY INVISIBLE (-3200 2800);
FORCEADD Q_CAP..1
(-3000 2950);
FORCEPROP 1 LAST LOCATION C562
J 0
(-2950 3050);
DISPLAY 0.978723 (-2950 3050);
PAINT WHITE (-2950 3050);
FORCEPROP 0 LAST $SEC 1
J 0
(-2950 3100);
DISPLAY 0.680851 (-2950 3100);
PAINT MONO (-2950 3100);
DISPLAY INVISIBLE (-2950 3100);
FORCEPROP 0 LAST CDS_SEC 1
J 0
(-2950 3100);
DISPLAY 0.680851 (-2950 3100);
DISPLAY INVISIBLE (-2950 3100);
FORCEPROP 1 LASTPIN (-3000 3050) $PN 1
J 0
(-2990 3030);
DISPLAY 0.787234 (-2990 3030);
PAINT MONO (-2990 3030);
FORCEPROP 1 LASTPIN (-3000 2850) $PN 2
J 0
(-2990 2830);
DISPLAY 0.787234 (-2990 2830);
PAINT MONO (-2990 2830);
FORCEPROP 1 LAST MATERIAL X6S
J 0
(-2950 2850);
DISPLAY 0.510638 (-2950 2850);
FORCEPROP 1 LAST VOLTAGE 4V
J 0
(-2950 2950);
DISPLAY 0.510638 (-2950 2950);
FORCEPROP 1 LAST VALUE 1UF
J 0
(-2950 3000);
DISPLAY 0.510638 (-2950 3000);
FORCEPROP 1 LAST TOLERANCE 20%
J 0
(-2950 2900);
DISPLAY 0.510638 (-2950 2900);
FORCEPROP 1 LAST PACK_TYPE 0201
J 0
(-2950 2800);
DISPLAY 0.510638 (-2950 2800);
FORCEPROP 2 LAST CDS_LIB pure_quanta
J 0
(-3000 2950);
DISPLAY INVISIBLE (-3000 2950);
FORCEPROP 1 LAST PATH I43
J 0
(-2950 3100);
DISPLAY 0.978723 (-2950 3100);
PAINT WHITE (-2950 3100);
DISPLAY INVISIBLE (-2950 3100);
FORCEPROP 1 LAST PART_NUMBER CH-10KMEE00
J 0
(-2950 2800);
DISPLAY 0.510638 (-2950 2800);
DISPLAY INVISIBLE (-2950 2800);
FORCEADD Q_CAP..1
(-3250 3575);
FORCEPROP 1 LAST LOCATION C579
J 0
(-3200 3675);
DISPLAY 0.978723 (-3200 3675);
PAINT WHITE (-3200 3675);
FORCEPROP 0 LAST $SEC 1
J 0
(-3200 3725);
DISPLAY 0.680851 (-3200 3725);
PAINT MONO (-3200 3725);
DISPLAY INVISIBLE (-3200 3725);
FORCEPROP 0 LAST CDS_SEC 1
J 0
(-3200 3725);
DISPLAY 0.680851 (-3200 3725);
DISPLAY INVISIBLE (-3200 3725);
FORCEPROP 1 LASTPIN (-3250 3675) $PN 1
J 0
(-3240 3655);
DISPLAY 0.787234 (-3240 3655);
PAINT MONO (-3240 3655);
FORCEPROP 1 LASTPIN (-3250 3475) $PN 2
J 0
(-3240 3455);
DISPLAY 0.787234 (-3240 3455);
PAINT MONO (-3240 3455);
FORCEPROP 1 LAST TOLERANCE 20%
J 0
(-3200 3525);
DISPLAY 0.510638 (-3200 3525);
FORCEPROP 1 LAST VALUE 10UF
J 0
(-3200 3625);
DISPLAY 0.510638 (-3200 3625);
FORCEPROP 1 LAST PACK_TYPE C0402
J 0
(-3200 3425);
DISPLAY 0.510638 (-3200 3425);
FORCEPROP 1 LAST VOLTAGE 6.3V
J 0
(-3200 3575);
DISPLAY 0.510638 (-3200 3575);
FORCEPROP 1 LAST MATERIAL X6S
J 0
(-3200 3475);
DISPLAY 0.510638 (-3200 3475);
FORCEPROP 2 LAST CDS_LIB pure_quanta
J 0
(-3250 3575);
DISPLAY INVISIBLE (-3250 3575);
FORCEPROP 1 LAST PATH I44
J 0
(-3200 3725);
DISPLAY 0.978723 (-3200 3725);
PAINT WHITE (-3200 3725);
DISPLAY INVISIBLE (-3200 3725);
FORCEPROP 1 LAST PART_NUMBER CH6101MEB01
J 0
(-3200 3425);
DISPLAY 0.978723 (-3200 3425);
DISPLAY INVISIBLE (-3200 3425);
FORCEADD Q_CAP..1
(-3025 3575);
FORCEPROP 1 LAST LOCATION C554
J 0
(-2975 3675);
DISPLAY 0.978723 (-2975 3675);
PAINT WHITE (-2975 3675);
FORCEPROP 0 LAST $SEC 1
J 0
(-2975 3725);
DISPLAY 0.680851 (-2975 3725);
PAINT MONO (-2975 3725);
DISPLAY INVISIBLE (-2975 3725);
FORCEPROP 0 LAST CDS_SEC 1
J 0
(-2975 3725);
DISPLAY 0.680851 (-2975 3725);
DISPLAY INVISIBLE (-2975 3725);
FORCEPROP 1 LASTPIN (-3025 3675) $PN 1
J 0
(-3015 3655);
DISPLAY 0.787234 (-3015 3655);
PAINT MONO (-3015 3655);
FORCEPROP 1 LASTPIN (-3025 3475) $PN 2
J 0
(-3015 3455);
DISPLAY 0.787234 (-3015 3455);
PAINT MONO (-3015 3455);
FORCEPROP 1 LAST PACK_TYPE 0402
J 0
(-2975 3425);
DISPLAY 0.510638 (-2975 3425);
FORCEPROP 1 LAST MATERIAL X6S
J 0
(-2975 3475);
DISPLAY 0.510638 (-2975 3475);
FORCEPROP 1 LAST VALUE 4.7UF
J 0
(-2975 3625);
DISPLAY 0.510638 (-2975 3625);
FORCEPROP 1 LAST TOLERANCE 20%
J 0
(-2975 3525);
DISPLAY 0.510638 (-2975 3525);
FORCEPROP 1 LAST VOLTAGE 6.3V
J 0
(-2975 3575);
DISPLAY 0.510638 (-2975 3575);
FORCEPROP 2 LAST CDS_LIB pure_quanta
J 0
(-3025 3575);
DISPLAY INVISIBLE (-3025 3575);
FORCEPROP 1 LAST PATH I45
J 0
(-2975 3725);
DISPLAY 0.978723 (-2975 3725);
PAINT WHITE (-2975 3725);
DISPLAY INVISIBLE (-2975 3725);
FORCEPROP 1 LAST PART_NUMBER CH5471MEB01
J 0
(-2975 3425);
DISPLAY 0.978723 (-2975 3425);
DISPLAY INVISIBLE (-2975 3425);
FORCEADD Q_CAP..1
(-2800 3575);
FORCEPROP 1 LAST LOCATION C571
J 0
(-2750 3675);
DISPLAY 0.978723 (-2750 3675);
PAINT WHITE (-2750 3675);
FORCEPROP 0 LAST $SEC 1
J 0
(-2750 3725);
DISPLAY 0.680851 (-2750 3725);
PAINT MONO (-2750 3725);
DISPLAY INVISIBLE (-2750 3725);
FORCEPROP 0 LAST CDS_SEC 1
J 0
(-2750 3725);
DISPLAY 0.680851 (-2750 3725);
DISPLAY INVISIBLE (-2750 3725);
FORCEPROP 1 LASTPIN (-2800 3675) $PN 1
J 0
(-2790 3655);
DISPLAY 0.787234 (-2790 3655);
PAINT MONO (-2790 3655);
FORCEPROP 1 LASTPIN (-2800 3475) $PN 2
J 0
(-2790 3455);
DISPLAY 0.787234 (-2790 3455);
PAINT MONO (-2790 3455);
FORCEPROP 1 LAST VOLTAGE 6.3V
J 0
(-2750 3575);
DISPLAY 0.510638 (-2750 3575);
FORCEPROP 1 LAST VALUE 4.7UF
J 0
(-2750 3625);
DISPLAY 0.510638 (-2750 3625);
FORCEPROP 1 LAST MATERIAL X6S
J 0
(-2750 3475);
DISPLAY 0.510638 (-2750 3475);
FORCEPROP 1 LAST PACK_TYPE 0402
J 0
(-2750 3425);
DISPLAY 0.510638 (-2750 3425);
FORCEPROP 1 LAST TOLERANCE 20%
J 0
(-2750 3525);
DISPLAY 0.510638 (-2750 3525);
FORCEPROP 2 LAST CDS_LIB pure_quanta
J 0
(-2800 3575);
DISPLAY INVISIBLE (-2800 3575);
FORCEPROP 1 LAST PATH I46
J 0
(-2750 3725);
DISPLAY 0.978723 (-2750 3725);
PAINT WHITE (-2750 3725);
DISPLAY INVISIBLE (-2750 3725);
FORCEPROP 1 LAST PART_NUMBER CH5471MEB01
J 0
(-2750 3425);
DISPLAY 0.978723 (-2750 3425);
DISPLAY INVISIBLE (-2750 3425);
FORCEADD Q_CAP..1
(-2675 2250);
FORCEPROP 1 LAST LOCATION C541
J 0
(-2625 2350);
DISPLAY 0.978723 (-2625 2350);
PAINT WHITE (-2625 2350);
FORCEPROP 0 LAST $SEC 1
J 0
(-2625 2400);
DISPLAY 0.680851 (-2625 2400);
PAINT MONO (-2625 2400);
DISPLAY INVISIBLE (-2625 2400);
FORCEPROP 0 LAST CDS_SEC 1
J 0
(-2625 2400);
DISPLAY 0.680851 (-2625 2400);
DISPLAY INVISIBLE (-2625 2400);
FORCEPROP 1 LASTPIN (-2675 2350) $PN 1
J 0
(-2665 2330);
DISPLAY 0.787234 (-2665 2330);
PAINT MONO (-2665 2330);
FORCEPROP 1 LASTPIN (-2675 2150) $PN 2
J 0
(-2665 2130);
DISPLAY 0.787234 (-2665 2130);
PAINT MONO (-2665 2130);
FORCEPROP 1 LAST VOLTAGE 10V
J 0
(-2625 2250);
DISPLAY 0.638298 (-2625 2250);
FORCEPROP 1 LAST PACK_TYPE C0201
J 0
(-2625 2100);
DISPLAY 0.638298 (-2625 2100);
FORCEPROP 1 LAST MATERIAL X7S
J 0
(-2625 2150);
DISPLAY 0.638298 (-2625 2150);
FORCEPROP 1 LAST TOLERANCE 10%
J 0
(-2625 2200);
DISPLAY 0.638298 (-2625 2200);
FORCEPROP 1 LAST VALUE 0.1UF
J 0
(-2625 2300);
DISPLAY 0.638298 (-2625 2300);
FORCEPROP 2 LAST CDS_LIB pure_quanta
J 0
(-2675 2250);
DISPLAY INVISIBLE (-2675 2250);
FORCEPROP 1 LAST PATH I48
J 0
(-2625 2400);
DISPLAY 0.978723 (-2625 2400);
PAINT WHITE (-2625 2400);
DISPLAY INVISIBLE (-2625 2400);
FORCEPROP 1 LAST PART_NUMBER CH4102K6E00
J 0
(-2625 2100);
DISPLAY 0.978723 (-2625 2100);
DISPLAY INVISIBLE (-2625 2100);
FORCEADD Q_CAP..1
(-2425 2250);
FORCEPROP 1 LAST LOCATION C582
J 0
(-2375 2350);
DISPLAY 0.978723 (-2375 2350);
PAINT WHITE (-2375 2350);
FORCEPROP 0 LAST $SEC 1
J 0
(-2375 2400);
DISPLAY 0.680851 (-2375 2400);
PAINT MONO (-2375 2400);
DISPLAY INVISIBLE (-2375 2400);
FORCEPROP 0 LAST CDS_SEC 1
J 0
(-2375 2400);
DISPLAY 0.680851 (-2375 2400);
DISPLAY INVISIBLE (-2375 2400);
FORCEPROP 1 LASTPIN (-2425 2350) $PN 1
J 0
(-2415 2330);
DISPLAY 0.787234 (-2415 2330);
PAINT MONO (-2415 2330);
FORCEPROP 1 LASTPIN (-2425 2150) $PN 2
J 0
(-2415 2130);
DISPLAY 0.787234 (-2415 2130);
PAINT MONO (-2415 2130);
FORCEPROP 1 LAST TOLERANCE 10%
J 0
(-2375 2200);
DISPLAY 0.638298 (-2375 2200);
FORCEPROP 1 LAST MATERIAL X7S
J 0
(-2375 2150);
DISPLAY 0.638298 (-2375 2150);
FORCEPROP 1 LAST PACK_TYPE C0201
J 0
(-2375 2100);
DISPLAY 0.638298 (-2375 2100);
FORCEPROP 1 LAST VOLTAGE 10V
J 0
(-2375 2250);
DISPLAY 0.638298 (-2375 2250);
FORCEPROP 1 LAST VALUE 0.1UF
J 0
(-2375 2300);
DISPLAY 0.638298 (-2375 2300);
FORCEPROP 2 LAST CDS_LIB pure_quanta
J 0
(-2425 2250);
DISPLAY INVISIBLE (-2425 2250);
FORCEPROP 1 LAST PATH I49
J 0
(-2375 2400);
DISPLAY 0.978723 (-2375 2400);
PAINT WHITE (-2375 2400);
DISPLAY INVISIBLE (-2375 2400);
FORCEPROP 1 LAST PART_NUMBER CH4102K6E00
J 0
(-2375 2100);
DISPLAY 0.978723 (-2375 2100);
DISPLAY INVISIBLE (-2375 2100);
FORCEADD Q_RES..1
(-7700 3775);
FORCEPROP 1 LAST LOCATION R951
J 0
(-7975 3800);
DISPLAY 0.808511 (-7975 3800);
FORCEPROP 2 LAST SEC 1
J 0
(-7750 3975);
DISPLAY 0.680851 (-7750 3975);
PAINT MONO (-7750 3975);
DISPLAY INVISIBLE (-7750 3975);
FORCEPROP 1 LASTPIN (-7800 3775) $PN 1
J 0
(-7788 3787);
DISPLAY 0.787234 (-7788 3787);
PAINT MONO (-7788 3787);
FORCEPROP 1 LASTPIN (-7600 3775) $PN 2
J 0
(-7638 3787);
DISPLAY 0.787234 (-7638 3787);
PAINT MONO (-7638 3787);
FORCEPROP 1 LAST MATERIAL EMPTY
J 0
(-7675 3675);
DISPLAY 0.638298 (-7675 3675);
PAINT RED (-7675 3675);
FORCEPROP 1 LAST WATTAGE 1/16W
J 2
(-7700 3675);
DISPLAY 0.638298 (-7700 3675);
FORCEPROP 1 LAST PACK_TYPE 0402LF
J 0
(-7850 3725);
DISPLAY 0.638298 (-7850 3725);
FORCEPROP 1 LAST TOLERANCE 5%
J 0
(-7650 3725);
DISPLAY 0.638298 (-7650 3725);
FORCEPROP 1 LAST VALUE 0
J 2
(-7550 3800);
DISPLAY 0.638298 (-7550 3800);
FORCEPROP 2 LAST SEC_TYPE 0402LF
J 0
(-7750 3975);
DISPLAY 0.680851 (-7750 3975);
DISPLAY INVISIBLE (-7750 3975);
FORCEPROP 2 LAST CDS_LIB pure_quanta
J 0
(-7700 3775);
DISPLAY INVISIBLE (-7700 3775);
FORCEPROP 1 LAST PATH I5
J 0
(-7750 3925);
DISPLAY 0.978723 (-7750 3925);
PAINT WHITE (-7750 3925);
DISPLAY INVISIBLE (-7750 3925);
FORCEPROP 1 LAST PART_NUMBER CS00002JB13
J 0
(-7750 3875);
DISPLAY 0.978723 (-7750 3875);
DISPLAY INVISIBLE (-7750 3875);
FORCEADD Q_CAP..1
(-2175 2250);
FORCEPROP 1 LAST LOCATION C523
J 0
(-2125 2350);
DISPLAY 0.978723 (-2125 2350);
PAINT WHITE (-2125 2350);
FORCEPROP 0 LAST $SEC 1
J 0
(-2125 2400);
DISPLAY 0.680851 (-2125 2400);
PAINT MONO (-2125 2400);
DISPLAY INVISIBLE (-2125 2400);
FORCEPROP 0 LAST CDS_SEC 1
J 0
(-2125 2400);
DISPLAY 0.680851 (-2125 2400);
DISPLAY INVISIBLE (-2125 2400);
FORCEPROP 1 LASTPIN (-2175 2350) $PN 1
J 0
(-2165 2330);
DISPLAY 0.787234 (-2165 2330);
PAINT MONO (-2165 2330);
FORCEPROP 1 LASTPIN (-2175 2150) $PN 2
J 0
(-2165 2130);
DISPLAY 0.787234 (-2165 2130);
PAINT MONO (-2165 2130);
FORCEPROP 1 LAST VALUE 0.1UF
J 0
(-2125 2300);
DISPLAY 0.638298 (-2125 2300);
FORCEPROP 1 LAST MATERIAL X7S
J 0
(-2125 2150);
DISPLAY 0.638298 (-2125 2150);
FORCEPROP 1 LAST PACK_TYPE C0201
J 0
(-2125 2100);
DISPLAY 0.638298 (-2125 2100);
FORCEPROP 1 LAST TOLERANCE 10%
J 0
(-2125 2200);
DISPLAY 0.638298 (-2125 2200);
FORCEPROP 1 LAST VOLTAGE 10V
J 0
(-2125 2250);
DISPLAY 0.638298 (-2125 2250);
FORCEPROP 2 LAST CDS_LIB pure_quanta
J 0
(-2175 2250);
DISPLAY INVISIBLE (-2175 2250);
FORCEPROP 1 LAST PATH I50
J 0
(-2125 2400);
DISPLAY 0.978723 (-2125 2400);
PAINT WHITE (-2125 2400);
DISPLAY INVISIBLE (-2125 2400);
FORCEPROP 1 LAST PART_NUMBER CH4102K6E00
J 0
(-2125 2100);
DISPLAY 0.978723 (-2125 2100);
DISPLAY INVISIBLE (-2125 2100);
FORCEADD Q_CAP..1
(-1900 2250);
FORCEPROP 1 LAST LOCATION C585
J 0
(-1850 2350);
DISPLAY 0.978723 (-1850 2350);
PAINT WHITE (-1850 2350);
FORCEPROP 0 LAST $SEC 1
J 0
(-1850 2400);
DISPLAY 0.680851 (-1850 2400);
PAINT MONO (-1850 2400);
DISPLAY INVISIBLE (-1850 2400);
FORCEPROP 0 LAST CDS_SEC 1
J 0
(-1850 2400);
DISPLAY 0.680851 (-1850 2400);
DISPLAY INVISIBLE (-1850 2400);
FORCEPROP 1 LASTPIN (-1900 2350) $PN 1
J 0
(-1890 2330);
DISPLAY 0.787234 (-1890 2330);
PAINT MONO (-1890 2330);
FORCEPROP 1 LASTPIN (-1900 2150) $PN 2
J 0
(-1890 2130);
DISPLAY 0.787234 (-1890 2130);
PAINT MONO (-1890 2130);
FORCEPROP 1 LAST TOLERANCE 10%
J 0
(-1850 2200);
DISPLAY 0.638298 (-1850 2200);
FORCEPROP 1 LAST VOLTAGE 10V
J 0
(-1850 2250);
DISPLAY 0.638298 (-1850 2250);
FORCEPROP 1 LAST PACK_TYPE C0201
J 0
(-1850 2100);
DISPLAY 0.638298 (-1850 2100);
FORCEPROP 1 LAST MATERIAL X7S
J 0
(-1850 2150);
DISPLAY 0.638298 (-1850 2150);
FORCEPROP 1 LAST VALUE 0.1UF
J 0
(-1850 2300);
DISPLAY 0.638298 (-1850 2300);
FORCEPROP 2 LAST CDS_LIB pure_quanta
J 0
(-1900 2250);
DISPLAY INVISIBLE (-1900 2250);
FORCEPROP 1 LAST PATH I51
J 0
(-1850 2400);
DISPLAY 0.978723 (-1850 2400);
PAINT WHITE (-1850 2400);
DISPLAY INVISIBLE (-1850 2400);
FORCEPROP 1 LAST PART_NUMBER CH4102K6E00
J 0
(-1850 2100);
DISPLAY 0.978723 (-1850 2100);
DISPLAY INVISIBLE (-1850 2100);
FORCEADD Q_CAP..1
(-2725 2950);
FORCEPROP 1 LAST LOCATION C570
J 0
(-2675 3050);
DISPLAY 0.978723 (-2675 3050);
PAINT WHITE (-2675 3050);
FORCEPROP 0 LAST $SEC 1
J 0
(-2675 3100);
DISPLAY 0.680851 (-2675 3100);
PAINT MONO (-2675 3100);
DISPLAY INVISIBLE (-2675 3100);
FORCEPROP 0 LAST CDS_SEC 1
J 0
(-2675 3100);
DISPLAY 0.680851 (-2675 3100);
DISPLAY INVISIBLE (-2675 3100);
FORCEPROP 1 LASTPIN (-2725 3050) $PN 1
J 0
(-2715 3030);
DISPLAY 0.787234 (-2715 3030);
PAINT MONO (-2715 3030);
FORCEPROP 1 LASTPIN (-2725 2850) $PN 2
J 0
(-2715 2830);
DISPLAY 0.787234 (-2715 2830);
PAINT MONO (-2715 2830);
FORCEPROP 1 LAST VALUE 1UF
J 0
(-2675 3000);
DISPLAY 0.510638 (-2675 3000);
FORCEPROP 1 LAST MATERIAL X6S
J 0
(-2675 2850);
DISPLAY 0.510638 (-2675 2850);
FORCEPROP 1 LAST VOLTAGE 4V
J 0
(-2675 2950);
DISPLAY 0.510638 (-2675 2950);
FORCEPROP 1 LAST TOLERANCE 20%
J 0
(-2675 2900);
DISPLAY 0.510638 (-2675 2900);
FORCEPROP 1 LAST PACK_TYPE 0201
J 0
(-2675 2800);
DISPLAY 0.510638 (-2675 2800);
FORCEPROP 2 LAST CDS_LIB pure_quanta
J 0
(-2725 2950);
DISPLAY INVISIBLE (-2725 2950);
FORCEPROP 1 LAST PATH I52
J 0
(-2675 3100);
DISPLAY 0.978723 (-2675 3100);
PAINT WHITE (-2675 3100);
DISPLAY INVISIBLE (-2675 3100);
FORCEPROP 1 LAST PART_NUMBER CH-10KMEE00
J 0
(-2675 2800);
DISPLAY 0.510638 (-2675 2800);
DISPLAY INVISIBLE (-2675 2800);
FORCEADD Q_CAP..1
(-2450 2950);
FORCEPROP 1 LAST LOCATION C573
J 0
(-2400 3050);
DISPLAY 0.978723 (-2400 3050);
PAINT WHITE (-2400 3050);
FORCEPROP 0 LAST $SEC 1
J 0
(-2400 3100);
DISPLAY 0.680851 (-2400 3100);
PAINT MONO (-2400 3100);
DISPLAY INVISIBLE (-2400 3100);
FORCEPROP 0 LAST CDS_SEC 1
J 0
(-2400 3100);
DISPLAY 0.680851 (-2400 3100);
DISPLAY INVISIBLE (-2400 3100);
FORCEPROP 1 LASTPIN (-2450 3050) $PN 1
J 0
(-2440 3030);
DISPLAY 0.787234 (-2440 3030);
PAINT MONO (-2440 3030);
FORCEPROP 1 LASTPIN (-2450 2850) $PN 2
J 0
(-2440 2830);
DISPLAY 0.787234 (-2440 2830);
PAINT MONO (-2440 2830);
FORCEPROP 1 LAST PACK_TYPE 0201
J 0
(-2400 2800);
DISPLAY 0.510638 (-2400 2800);
FORCEPROP 1 LAST TOLERANCE 20%
J 0
(-2400 2900);
DISPLAY 0.510638 (-2400 2900);
FORCEPROP 1 LAST VALUE 1UF
J 0
(-2400 3000);
DISPLAY 0.510638 (-2400 3000);
FORCEPROP 1 LAST VOLTAGE 4V
J 0
(-2400 2950);
DISPLAY 0.510638 (-2400 2950);
FORCEPROP 1 LAST MATERIAL X6S
J 0
(-2400 2850);
DISPLAY 0.510638 (-2400 2850);
FORCEPROP 2 LAST CDS_LIB pure_quanta
J 0
(-2450 2950);
DISPLAY INVISIBLE (-2450 2950);
FORCEPROP 1 LAST PATH I53
J 0
(-2400 3100);
DISPLAY 0.978723 (-2400 3100);
PAINT WHITE (-2400 3100);
DISPLAY INVISIBLE (-2400 3100);
FORCEPROP 1 LAST PART_NUMBER CH-10KMEE00
J 0
(-2400 2800);
DISPLAY 0.510638 (-2400 2800);
DISPLAY INVISIBLE (-2400 2800);
FORCEADD Q_CAP..1
(-2550 3575);
FORCEPROP 1 LAST LOCATION C557
J 0
(-2500 3675);
DISPLAY 0.978723 (-2500 3675);
PAINT WHITE (-2500 3675);
FORCEPROP 0 LAST $SEC 1
J 0
(-2500 3725);
DISPLAY 0.680851 (-2500 3725);
PAINT MONO (-2500 3725);
DISPLAY INVISIBLE (-2500 3725);
FORCEPROP 0 LAST CDS_SEC 1
J 0
(-2500 3725);
DISPLAY 0.680851 (-2500 3725);
DISPLAY INVISIBLE (-2500 3725);
FORCEPROP 1 LASTPIN (-2550 3675) $PN 1
J 0
(-2540 3655);
DISPLAY 0.787234 (-2540 3655);
PAINT MONO (-2540 3655);
FORCEPROP 1 LASTPIN (-2550 3475) $PN 2
J 0
(-2540 3455);
DISPLAY 0.787234 (-2540 3455);
PAINT MONO (-2540 3455);
FORCEPROP 1 LAST PACK_TYPE 0402
J 0
(-2500 3425);
DISPLAY 0.510638 (-2500 3425);
FORCEPROP 1 LAST MATERIAL X6S
J 0
(-2500 3475);
DISPLAY 0.510638 (-2500 3475);
FORCEPROP 1 LAST TOLERANCE 20%
J 0
(-2500 3525);
DISPLAY 0.510638 (-2500 3525);
FORCEPROP 1 LAST VALUE 4.7UF
J 0
(-2500 3625);
DISPLAY 0.510638 (-2500 3625);
FORCEPROP 1 LAST VOLTAGE 6.3V
J 0
(-2500 3575);
DISPLAY 0.510638 (-2500 3575);
FORCEPROP 2 LAST CDS_LIB pure_quanta
J 0
(-2550 3575);
DISPLAY INVISIBLE (-2550 3575);
FORCEPROP 1 LAST PATH I54
J 0
(-2500 3725);
DISPLAY 0.978723 (-2500 3725);
PAINT WHITE (-2500 3725);
DISPLAY INVISIBLE (-2500 3725);
FORCEPROP 1 LAST PART_NUMBER CH5471MEB01
J 0
(-2500 3425);
DISPLAY 0.978723 (-2500 3425);
DISPLAY INVISIBLE (-2500 3425);
FORCEADD Q_CAP..1
(-2325 3575);
FORCEPROP 1 LAST LOCATION C572
J 0
(-2275 3675);
DISPLAY 0.978723 (-2275 3675);
PAINT WHITE (-2275 3675);
FORCEPROP 0 LAST $SEC 1
J 0
(-2275 3725);
DISPLAY 0.680851 (-2275 3725);
PAINT MONO (-2275 3725);
DISPLAY INVISIBLE (-2275 3725);
FORCEPROP 0 LAST CDS_SEC 1
J 0
(-2275 3725);
DISPLAY 0.680851 (-2275 3725);
DISPLAY INVISIBLE (-2275 3725);
FORCEPROP 1 LASTPIN (-2325 3675) $PN 1
J 0
(-2315 3655);
DISPLAY 0.787234 (-2315 3655);
PAINT MONO (-2315 3655);
FORCEPROP 1 LASTPIN (-2325 3475) $PN 2
J 0
(-2315 3455);
DISPLAY 0.787234 (-2315 3455);
PAINT MONO (-2315 3455);
FORCEPROP 1 LAST PACK_TYPE 0402
J 0
(-2275 3425);
DISPLAY 0.510638 (-2275 3425);
FORCEPROP 1 LAST VOLTAGE 6.3V
J 0
(-2275 3575);
DISPLAY 0.510638 (-2275 3575);
FORCEPROP 1 LAST VALUE 4.7UF
J 0
(-2275 3625);
DISPLAY 0.510638 (-2275 3625);
FORCEPROP 1 LAST TOLERANCE 20%
J 0
(-2275 3525);
DISPLAY 0.510638 (-2275 3525);
FORCEPROP 1 LAST MATERIAL X6S
J 0
(-2275 3475);
DISPLAY 0.510638 (-2275 3475);
FORCEPROP 2 LAST CDS_LIB pure_quanta
J 0
(-2325 3575);
DISPLAY INVISIBLE (-2325 3575);
FORCEPROP 1 LAST PATH I55
J 0
(-2275 3725);
DISPLAY 0.978723 (-2275 3725);
PAINT WHITE (-2275 3725);
DISPLAY INVISIBLE (-2275 3725);
FORCEPROP 1 LAST PART_NUMBER CH5471MEB01
J 0
(-2275 3425);
DISPLAY 0.978723 (-2275 3425);
DISPLAY INVISIBLE (-2275 3425);
FORCEADD Q_CAP..1
(-2200 2925);
FORCEPROP 1 LAST LOCATION C577
J 0
(-2150 3025);
DISPLAY 0.978723 (-2150 3025);
PAINT WHITE (-2150 3025);
FORCEPROP 0 LAST $SEC 1
J 0
(-2150 3075);
DISPLAY 0.680851 (-2150 3075);
PAINT MONO (-2150 3075);
DISPLAY INVISIBLE (-2150 3075);
FORCEPROP 0 LAST CDS_SEC 1
J 0
(-2150 3075);
DISPLAY 0.680851 (-2150 3075);
DISPLAY INVISIBLE (-2150 3075);
FORCEPROP 1 LASTPIN (-2200 3025) $PN 1
J 0
(-2190 3005);
DISPLAY 0.787234 (-2190 3005);
PAINT MONO (-2190 3005);
FORCEPROP 1 LASTPIN (-2200 2825) $PN 2
J 0
(-2190 2805);
DISPLAY 0.787234 (-2190 2805);
PAINT MONO (-2190 2805);
FORCEPROP 1 LAST MATERIAL X6S
J 0
(-2150 2825);
DISPLAY 0.510638 (-2150 2825);
FORCEPROP 1 LAST VALUE 1UF
J 0
(-2150 2975);
DISPLAY 0.510638 (-2150 2975);
FORCEPROP 1 LAST VOLTAGE 4V
J 0
(-2150 2925);
DISPLAY 0.510638 (-2150 2925);
FORCEPROP 1 LAST TOLERANCE 20%
J 0
(-2150 2875);
DISPLAY 0.510638 (-2150 2875);
FORCEPROP 1 LAST PACK_TYPE 0201
J 0
(-2150 2775);
DISPLAY 0.510638 (-2150 2775);
FORCEPROP 2 LAST CDS_LIB pure_quanta
J 0
(-2200 2925);
DISPLAY INVISIBLE (-2200 2925);
FORCEPROP 1 LAST PATH I56
J 0
(-2150 3075);
DISPLAY 0.978723 (-2150 3075);
PAINT WHITE (-2150 3075);
DISPLAY INVISIBLE (-2150 3075);
FORCEPROP 1 LAST PART_NUMBER CH-10KMEE00
J 0
(-2150 2775);
DISPLAY 0.510638 (-2150 2775);
DISPLAY INVISIBLE (-2150 2775);
FORCEADD Q_CAP..1
(-1925 2925);
FORCEPROP 1 LAST LOCATION C581
J 0
(-1875 3025);
DISPLAY 0.978723 (-1875 3025);
PAINT WHITE (-1875 3025);
FORCEPROP 0 LAST $SEC 1
J 0
(-1875 3075);
DISPLAY 0.680851 (-1875 3075);
PAINT MONO (-1875 3075);
DISPLAY INVISIBLE (-1875 3075);
FORCEPROP 0 LAST CDS_SEC 1
J 0
(-1875 3075);
DISPLAY 0.680851 (-1875 3075);
DISPLAY INVISIBLE (-1875 3075);
FORCEPROP 1 LASTPIN (-1925 3025) $PN 1
J 0
(-1915 3005);
DISPLAY 0.787234 (-1915 3005);
PAINT MONO (-1915 3005);
FORCEPROP 1 LASTPIN (-1925 2825) $PN 2
J 0
(-1915 2805);
DISPLAY 0.787234 (-1915 2805);
PAINT MONO (-1915 2805);
FORCEPROP 1 LAST TOLERANCE 20%
J 0
(-1875 2875);
DISPLAY 0.510638 (-1875 2875);
FORCEPROP 1 LAST MATERIAL X6S
J 0
(-1875 2825);
DISPLAY 0.510638 (-1875 2825);
FORCEPROP 1 LAST VALUE 1UF
J 0
(-1875 2975);
DISPLAY 0.510638 (-1875 2975);
FORCEPROP 1 LAST VOLTAGE 4V
J 0
(-1875 2925);
DISPLAY 0.510638 (-1875 2925);
FORCEPROP 1 LAST PACK_TYPE 0201
J 0
(-1875 2775);
DISPLAY 0.510638 (-1875 2775);
FORCEPROP 2 LAST CDS_LIB pure_quanta
J 0
(-1925 2925);
DISPLAY INVISIBLE (-1925 2925);
FORCEPROP 1 LAST PATH I57
J 0
(-1875 3075);
DISPLAY 0.978723 (-1875 3075);
PAINT WHITE (-1875 3075);
DISPLAY INVISIBLE (-1875 3075);
FORCEPROP 1 LAST PART_NUMBER CH-10KMEE00
J 0
(-1875 2775);
DISPLAY 0.510638 (-1875 2775);
DISPLAY INVISIBLE (-1875 2775);
FORCEADD Q_CAP..1
(-2100 3575);
FORCEPROP 1 LAST LOCATION C525
J 0
(-2050 3675);
DISPLAY 0.978723 (-2050 3675);
PAINT WHITE (-2050 3675);
FORCEPROP 0 LAST $SEC 1
J 0
(-2050 3725);
DISPLAY 0.680851 (-2050 3725);
PAINT MONO (-2050 3725);
DISPLAY INVISIBLE (-2050 3725);
FORCEPROP 0 LAST CDS_SEC 1
J 0
(-2050 3725);
DISPLAY 0.680851 (-2050 3725);
DISPLAY INVISIBLE (-2050 3725);
FORCEPROP 1 LASTPIN (-2100 3675) $PN 1
J 0
(-2090 3655);
DISPLAY 0.787234 (-2090 3655);
PAINT MONO (-2090 3655);
FORCEPROP 1 LASTPIN (-2100 3475) $PN 2
J 0
(-2090 3455);
DISPLAY 0.787234 (-2090 3455);
PAINT MONO (-2090 3455);
FORCEPROP 1 LAST PACK_TYPE 0201
J 0
(-2050 3425);
DISPLAY 0.510638 (-2050 3425);
FORCEPROP 1 LAST VOLTAGE 4V
J 0
(-2050 3575);
DISPLAY 0.510638 (-2050 3575);
FORCEPROP 1 LAST VALUE 1UF
J 0
(-2050 3625);
DISPLAY 0.510638 (-2050 3625);
FORCEPROP 1 LAST TOLERANCE 20%
J 0
(-2050 3525);
DISPLAY 0.510638 (-2050 3525);
FORCEPROP 1 LAST MATERIAL X6S
J 0
(-2050 3475);
DISPLAY 0.510638 (-2050 3475);
FORCEPROP 2 LAST CDS_LIB pure_quanta
J 0
(-2100 3575);
DISPLAY INVISIBLE (-2100 3575);
FORCEPROP 1 LAST PATH I58
J 0
(-2050 3725);
DISPLAY 0.978723 (-2050 3725);
PAINT WHITE (-2050 3725);
DISPLAY INVISIBLE (-2050 3725);
FORCEPROP 1 LAST PART_NUMBER CH-10KMEE00
J 0
(-2050 3425);
DISPLAY 0.510638 (-2050 3425);
DISPLAY INVISIBLE (-2050 3425);
FORCEADD Q_CAP..1
(-1875 3575);
FORCEPROP 1 LAST LOCATION C529
J 0
(-1825 3675);
DISPLAY 0.978723 (-1825 3675);
PAINT WHITE (-1825 3675);
FORCEPROP 0 LAST $SEC 1
J 0
(-1825 3725);
DISPLAY 0.680851 (-1825 3725);
PAINT MONO (-1825 3725);
DISPLAY INVISIBLE (-1825 3725);
FORCEPROP 0 LAST CDS_SEC 1
J 0
(-1825 3725);
DISPLAY 0.680851 (-1825 3725);
DISPLAY INVISIBLE (-1825 3725);
FORCEPROP 1 LASTPIN (-1875 3675) $PN 1
J 0
(-1865 3655);
DISPLAY 0.787234 (-1865 3655);
PAINT MONO (-1865 3655);
FORCEPROP 1 LASTPIN (-1875 3475) $PN 2
J 0
(-1865 3455);
DISPLAY 0.787234 (-1865 3455);
PAINT MONO (-1865 3455);
FORCEPROP 1 LAST VOLTAGE 4V
J 0
(-1825 3575);
DISPLAY 0.510638 (-1825 3575);
FORCEPROP 1 LAST PACK_TYPE 0201
J 0
(-1825 3425);
DISPLAY 0.510638 (-1825 3425);
FORCEPROP 1 LAST VALUE 1UF
J 0
(-1825 3625);
DISPLAY 0.510638 (-1825 3625);
FORCEPROP 1 LAST MATERIAL X6S
J 0
(-1825 3475);
DISPLAY 0.510638 (-1825 3475);
FORCEPROP 1 LAST TOLERANCE 20%
J 0
(-1825 3525);
DISPLAY 0.510638 (-1825 3525);
FORCEPROP 2 LAST CDS_LIB pure_quanta
J 0
(-1875 3575);
DISPLAY INVISIBLE (-1875 3575);
FORCEPROP 1 LAST PATH I59
J 0
(-1825 3725);
DISPLAY 0.978723 (-1825 3725);
PAINT WHITE (-1825 3725);
DISPLAY INVISIBLE (-1825 3725);
FORCEPROP 1 LAST PART_NUMBER CH-10KMEE00
J 0
(-1825 3425);
DISPLAY 0.510638 (-1825 3425);
DISPLAY INVISIBLE (-1825 3425);
FORCEADD P1V0..1
(-6900 3500);
FORCEPROP 3 LASTPIN (-6900 3450) SIG_NAME P1V8_CPU0_RT0_1A_1D\g
J 0
(-6890 3460);
DISPLAY 0.659574 (-6890 3460);
PAINT MONO (-6890 3460);
DISPLAY INVISIBLE (-6890 3460);
FORCEPROP 1 LAST HDL_POWER P1V8_CPU0_RT0_1A_1D
J 1
(-6900 3550);
DISPLAY 0.489362 (-6900 3550);
PAINT SKYBLUE (-6900 3550);
FORCEPROP 2 LAST CDS_LIB pure_quanta_power
J 0
(-6900 3500);
DISPLAY INVISIBLE (-6900 3500);
FORCEPROP 1 LAST PATH I6
J 0
(-6850 3525);
DISPLAY 0.872340 (-6850 3525);
PAINT AQUA (-6850 3525);
DISPLAY INVISIBLE (-6850 3525);
FORCEADD Q_CAP..1
(-1625 2250);
FORCEPROP 1 LAST LOCATION C558
J 0
(-1575 2350);
DISPLAY 0.978723 (-1575 2350);
PAINT WHITE (-1575 2350);
FORCEPROP 0 LAST $SEC 1
J 0
(-1575 2400);
DISPLAY 0.680851 (-1575 2400);
PAINT MONO (-1575 2400);
DISPLAY INVISIBLE (-1575 2400);
FORCEPROP 0 LAST CDS_SEC 1
J 0
(-1575 2400);
DISPLAY 0.680851 (-1575 2400);
DISPLAY INVISIBLE (-1575 2400);
FORCEPROP 1 LASTPIN (-1625 2350) $PN 1
J 0
(-1615 2330);
DISPLAY 0.787234 (-1615 2330);
PAINT MONO (-1615 2330);
FORCEPROP 1 LASTPIN (-1625 2150) $PN 2
J 0
(-1615 2130);
DISPLAY 0.787234 (-1615 2130);
PAINT MONO (-1615 2130);
FORCEPROP 1 LAST TOLERANCE 10%
J 0
(-1575 2200);
DISPLAY 0.638298 (-1575 2200);
FORCEPROP 1 LAST VOLTAGE 10V
J 0
(-1575 2250);
DISPLAY 0.638298 (-1575 2250);
FORCEPROP 1 LAST VALUE 0.1UF
J 0
(-1575 2300);
DISPLAY 0.638298 (-1575 2300);
FORCEPROP 1 LAST PACK_TYPE C0201
J 0
(-1575 2100);
DISPLAY 0.638298 (-1575 2100);
FORCEPROP 1 LAST MATERIAL X7S
J 0
(-1575 2150);
DISPLAY 0.638298 (-1575 2150);
FORCEPROP 2 LAST CDS_LIB pure_quanta
J 0
(-1625 2250);
DISPLAY INVISIBLE (-1625 2250);
FORCEPROP 1 LAST PATH I60
J 0
(-1575 2400);
DISPLAY 0.978723 (-1575 2400);
PAINT WHITE (-1575 2400);
DISPLAY INVISIBLE (-1575 2400);
FORCEPROP 1 LAST PART_NUMBER CH4102K6E00
J 0
(-1575 2100);
DISPLAY 0.978723 (-1575 2100);
DISPLAY INVISIBLE (-1575 2100);
FORCEADD UNIVERSAL_GND..1
(-1375 1825);
FORCEPROP 3 LASTPIN (-1375 1875) SIG_NAME GND\g
J 0
(-1365 1885);
DISPLAY 0.659574 (-1365 1885);
PAINT MONO (-1365 1885);
DISPLAY INVISIBLE (-1365 1885);
FORCEPROP 2 LAST CDS_LIB pure_quanta_power
J 0
(-1375 1825);
DISPLAY INVISIBLE (-1375 1825);
FORCEPROP 1 LAST HDL_POWER GND
J 1
(-1350 1750);
DISPLAY 0.872340 (-1350 1750);
PAINT GREEN (-1350 1750);
DISPLAY INVISIBLE (-1350 1750);
FORCEPROP 1 LAST PATH I61
J 0
(-1300 1825);
DISPLAY 0.872340 (-1300 1825);
PAINT AQUA (-1300 1825);
DISPLAY INVISIBLE (-1300 1825);
FORCEADD Q_CAP..1
(-1375 2250);
FORCEPROP 1 LAST LOCATION C543
J 0
(-1325 2350);
DISPLAY 0.978723 (-1325 2350);
PAINT WHITE (-1325 2350);
FORCEPROP 0 LAST $SEC 1
J 0
(-1325 2400);
DISPLAY 0.680851 (-1325 2400);
PAINT MONO (-1325 2400);
DISPLAY INVISIBLE (-1325 2400);
FORCEPROP 0 LAST CDS_SEC 1
J 0
(-1325 2400);
DISPLAY 0.680851 (-1325 2400);
DISPLAY INVISIBLE (-1325 2400);
FORCEPROP 1 LASTPIN (-1375 2350) $PN 1
J 0
(-1365 2330);
DISPLAY 0.787234 (-1365 2330);
PAINT MONO (-1365 2330);
FORCEPROP 1 LASTPIN (-1375 2150) $PN 2
J 0
(-1365 2130);
DISPLAY 0.787234 (-1365 2130);
PAINT MONO (-1365 2130);
FORCEPROP 1 LAST MATERIAL X7S
J 0
(-1325 2150);
DISPLAY 0.638298 (-1325 2150);
FORCEPROP 1 LAST VALUE 0.1UF
J 0
(-1325 2300);
DISPLAY 0.638298 (-1325 2300);
FORCEPROP 1 LAST VOLTAGE 10V
J 0
(-1325 2250);
DISPLAY 0.638298 (-1325 2250);
FORCEPROP 1 LAST TOLERANCE 10%
J 0
(-1325 2200);
DISPLAY 0.638298 (-1325 2200);
FORCEPROP 1 LAST PACK_TYPE C0201
J 0
(-1325 2100);
DISPLAY 0.638298 (-1325 2100);
FORCEPROP 2 LAST CDS_LIB pure_quanta
J 0
(-1375 2250);
DISPLAY INVISIBLE (-1375 2250);
FORCEPROP 1 LAST PATH I62
J 0
(-1325 2400);
DISPLAY 0.978723 (-1325 2400);
PAINT WHITE (-1325 2400);
DISPLAY INVISIBLE (-1325 2400);
FORCEPROP 1 LAST PART_NUMBER CH4102K6E00
J 0
(-1325 2100);
DISPLAY 0.978723 (-1325 2100);
DISPLAY INVISIBLE (-1325 2100);
FORCEADD UNIVERSAL_GND..1
(-875 2550);
FORCEPROP 3 LASTPIN (-875 2600) SIG_NAME GND\g
J 0
(-865 2610);
DISPLAY 0.659574 (-865 2610);
PAINT MONO (-865 2610);
DISPLAY INVISIBLE (-865 2610);
FORCEPROP 2 LAST CDS_LIB pure_quanta_power
J 0
(-875 2550);
DISPLAY INVISIBLE (-875 2550);
FORCEPROP 1 LAST HDL_POWER GND
J 1
(-850 2475);
DISPLAY 0.872340 (-850 2475);
PAINT GREEN (-850 2475);
DISPLAY INVISIBLE (-850 2475);
FORCEPROP 1 LAST PATH I63
J 0
(-800 2550);
DISPLAY 0.872340 (-800 2550);
PAINT AQUA (-800 2550);
DISPLAY INVISIBLE (-800 2550);
FORCEADD Q_CAP..1
(-1650 3575);
FORCEPROP 1 LAST LOCATION C521
J 0
(-1600 3675);
DISPLAY 0.978723 (-1600 3675);
PAINT WHITE (-1600 3675);
FORCEPROP 0 LAST $SEC 1
J 0
(-1600 3725);
DISPLAY 0.680851 (-1600 3725);
PAINT MONO (-1600 3725);
DISPLAY INVISIBLE (-1600 3725);
FORCEPROP 0 LAST CDS_SEC 1
J 0
(-1600 3725);
DISPLAY 0.680851 (-1600 3725);
DISPLAY INVISIBLE (-1600 3725);
FORCEPROP 1 LASTPIN (-1650 3675) $PN 1
J 0
(-1640 3655);
DISPLAY 0.787234 (-1640 3655);
PAINT MONO (-1640 3655);
FORCEPROP 1 LASTPIN (-1650 3475) $PN 2
J 0
(-1640 3455);
DISPLAY 0.787234 (-1640 3455);
PAINT MONO (-1640 3455);
FORCEPROP 1 LAST MATERIAL X6S
J 0
(-1600 3475);
DISPLAY 0.510638 (-1600 3475);
FORCEPROP 1 LAST VALUE 1UF
J 0
(-1600 3625);
DISPLAY 0.510638 (-1600 3625);
FORCEPROP 1 LAST TOLERANCE 20%
J 0
(-1600 3525);
DISPLAY 0.510638 (-1600 3525);
FORCEPROP 1 LAST VOLTAGE 4V
J 0
(-1600 3575);
DISPLAY 0.510638 (-1600 3575);
FORCEPROP 1 LAST PACK_TYPE 0201
J 0
(-1600 3425);
DISPLAY 0.510638 (-1600 3425);
FORCEPROP 2 LAST CDS_LIB pure_quanta
J 0
(-1650 3575);
DISPLAY INVISIBLE (-1650 3575);
FORCEPROP 1 LAST PATH I65
J 0
(-1600 3725);
DISPLAY 0.978723 (-1600 3725);
PAINT WHITE (-1600 3725);
DISPLAY INVISIBLE (-1600 3725);
FORCEPROP 1 LAST PART_NUMBER CH-10KMEE00
J 0
(-1600 3425);
DISPLAY 0.510638 (-1600 3425);
DISPLAY INVISIBLE (-1600 3425);
FORCEADD Q_CAP..1
(-1400 3575);
FORCEPROP 1 LAST LOCATION C526
J 0
(-1350 3675);
DISPLAY 0.978723 (-1350 3675);
PAINT WHITE (-1350 3675);
FORCEPROP 0 LAST $SEC 1
J 0
(-1350 3725);
DISPLAY 0.680851 (-1350 3725);
PAINT MONO (-1350 3725);
DISPLAY INVISIBLE (-1350 3725);
FORCEPROP 0 LAST CDS_SEC 1
J 0
(-1350 3725);
DISPLAY 0.680851 (-1350 3725);
DISPLAY INVISIBLE (-1350 3725);
FORCEPROP 1 LASTPIN (-1400 3675) $PN 1
J 0
(-1390 3655);
DISPLAY 0.787234 (-1390 3655);
PAINT MONO (-1390 3655);
FORCEPROP 1 LASTPIN (-1400 3475) $PN 2
J 0
(-1390 3455);
DISPLAY 0.787234 (-1390 3455);
PAINT MONO (-1390 3455);
FORCEPROP 1 LAST TOLERANCE 20%
J 0
(-1350 3525);
DISPLAY 0.510638 (-1350 3525);
FORCEPROP 1 LAST MATERIAL X6S
J 0
(-1350 3475);
DISPLAY 0.510638 (-1350 3475);
FORCEPROP 1 LAST PACK_TYPE 0201
J 0
(-1350 3425);
DISPLAY 0.510638 (-1350 3425);
FORCEPROP 1 LAST VOLTAGE 4V
J 0
(-1350 3575);
DISPLAY 0.510638 (-1350 3575);
FORCEPROP 1 LAST VALUE 1UF
J 0
(-1350 3625);
DISPLAY 0.510638 (-1350 3625);
FORCEPROP 2 LAST CDS_LIB pure_quanta
J 0
(-1400 3575);
DISPLAY INVISIBLE (-1400 3575);
FORCEPROP 1 LAST PATH I66
J 0
(-1350 3725);
DISPLAY 0.978723 (-1350 3725);
PAINT WHITE (-1350 3725);
DISPLAY INVISIBLE (-1350 3725);
FORCEPROP 1 LAST PART_NUMBER CH-10KMEE00
J 0
(-1350 3425);
DISPLAY 0.510638 (-1350 3425);
DISPLAY INVISIBLE (-1350 3425);
FORCEADD Q_CAP..1
(-3475 4200);
FORCEPROP 1 LAST LOCATION C550
J 0
(-3425 4300);
DISPLAY 0.978723 (-3425 4300);
PAINT WHITE (-3425 4300);
FORCEPROP 0 LAST $SEC 1
J 0
(-3425 4350);
DISPLAY 0.680851 (-3425 4350);
PAINT MONO (-3425 4350);
DISPLAY INVISIBLE (-3425 4350);
FORCEPROP 0 LAST CDS_SEC 1
J 0
(-3425 4350);
DISPLAY 0.680851 (-3425 4350);
DISPLAY INVISIBLE (-3425 4350);
FORCEPROP 1 LASTPIN (-3475 4300) $PN 1
J 0
(-3465 4280);
DISPLAY 0.787234 (-3465 4280);
PAINT MONO (-3465 4280);
FORCEPROP 1 LASTPIN (-3475 4100) $PN 2
J 0
(-3465 4080);
DISPLAY 0.787234 (-3465 4080);
PAINT MONO (-3465 4080);
FORCEPROP 1 LAST TOLERANCE 20%
J 0
(-3425 4150);
DISPLAY 0.510638 (-3425 4150);
FORCEPROP 1 LAST VOLTAGE 4V
J 0
(-3425 4200);
DISPLAY 0.510638 (-3425 4200);
FORCEPROP 1 LAST MATERIAL X6S
J 0
(-3425 4100);
DISPLAY 0.510638 (-3425 4100);
FORCEPROP 1 LAST PACK_TYPE C0805
J 0
(-3425 4050);
DISPLAY 0.510638 (-3425 4050);
FORCEPROP 1 LAST VALUE 100UF
J 0
(-3425 4250);
DISPLAY 0.510638 (-3425 4250);
FORCEPROP 2 LAST CDS_LIB pure_quanta
J 0
(-3475 4200);
DISPLAY INVISIBLE (-3475 4200);
FORCEPROP 1 LAST PATH I67
J 0
(-3425 4350);
DISPLAY 0.978723 (-3425 4350);
PAINT WHITE (-3425 4350);
DISPLAY INVISIBLE (-3425 4350);
FORCEPROP 1 LAST PART_NUMBER CH710KMEA01
J 0
(-3425 4050);
DISPLAY 0.404255 (-3425 4050);
DISPLAY INVISIBLE (-3425 4050);
FORCEADD VCC_CORE..1
(-3350 4725);
FORCEPROP 3 LASTPIN (-3350 4675) SIG_NAME P0V9_CPU0_RT0_2A\g
J 0
(-3340 4685);
DISPLAY 0.659574 (-3340 4685);
PAINT MONO (-3340 4685);
DISPLAY INVISIBLE (-3340 4685);
FORCEPROP 1 LAST HDL_POWER P0V9_CPU0_RT0_2A
J 1
(-3350 4775);
DISPLAY 0.617021 (-3350 4775);
PAINT GREEN (-3350 4775);
FORCEPROP 2 LAST CDS_LIB pure_quanta_power
J 0
(-3350 4725);
DISPLAY INVISIBLE (-3350 4725);
FORCEPROP 1 LAST PATH I68
J 0
(-3300 4750);
DISPLAY 0.872340 (-3300 4750);
PAINT AQUA (-3300 4750);
DISPLAY INVISIBLE (-3300 4750);
FORCEADD Q_CAP..1
(-3250 4200);
FORCEPROP 1 LAST LOCATION C556
J 0
(-3200 4300);
DISPLAY 0.978723 (-3200 4300);
PAINT WHITE (-3200 4300);
FORCEPROP 0 LAST $SEC 1
J 0
(-3200 4350);
DISPLAY 0.680851 (-3200 4350);
PAINT MONO (-3200 4350);
DISPLAY INVISIBLE (-3200 4350);
FORCEPROP 0 LAST CDS_SEC 1
J 0
(-3200 4350);
DISPLAY 0.680851 (-3200 4350);
DISPLAY INVISIBLE (-3200 4350);
FORCEPROP 1 LASTPIN (-3250 4300) $PN 1
J 0
(-3240 4280);
DISPLAY 0.787234 (-3240 4280);
PAINT MONO (-3240 4280);
FORCEPROP 1 LASTPIN (-3250 4100) $PN 2
J 0
(-3240 4080);
DISPLAY 0.787234 (-3240 4080);
PAINT MONO (-3240 4080);
FORCEPROP 1 LAST PACK_TYPE C0805
J 0
(-3200 4050);
DISPLAY 0.510638 (-3200 4050);
FORCEPROP 1 LAST TOLERANCE 20%
J 0
(-3200 4150);
DISPLAY 0.510638 (-3200 4150);
FORCEPROP 1 LAST VALUE 100UF
J 0
(-3200 4250);
DISPLAY 0.510638 (-3200 4250);
FORCEPROP 1 LAST VOLTAGE 4V
J 0
(-3200 4200);
DISPLAY 0.510638 (-3200 4200);
FORCEPROP 1 LAST MATERIAL X6S
J 0
(-3200 4100);
DISPLAY 0.510638 (-3200 4100);
FORCEPROP 2 LAST CDS_LIB pure_quanta
J 0
(-3250 4200);
DISPLAY INVISIBLE (-3250 4200);
FORCEPROP 1 LAST PATH I69
J 0
(-3200 4350);
DISPLAY 0.978723 (-3200 4350);
PAINT WHITE (-3200 4350);
DISPLAY INVISIBLE (-3200 4350);
FORCEPROP 1 LAST PART_NUMBER CH710KMEA01
J 0
(-3200 4050);
DISPLAY 0.404255 (-3200 4050);
DISPLAY INVISIBLE (-3200 4050);
FORCEADD UNIVERSAL_GND..1
(-6500 2700);
FORCEPROP 3 LASTPIN (-6500 2750) SIG_NAME GND\g
J 0
(-6490 2760);
DISPLAY 0.659574 (-6490 2760);
PAINT MONO (-6490 2760);
DISPLAY INVISIBLE (-6490 2760);
FORCEPROP 2 LAST CDS_LIB pure_quanta_power
J 0
(-6500 2700);
DISPLAY INVISIBLE (-6500 2700);
FORCEPROP 1 LAST HDL_POWER GND
J 1
(-6475 2625);
DISPLAY 0.872340 (-6475 2625);
PAINT GREEN (-6475 2625);
DISPLAY INVISIBLE (-6475 2625);
FORCEPROP 1 LAST PATH I7
J 0
(-6425 2700);
DISPLAY 0.872340 (-6425 2700);
PAINT AQUA (-6425 2700);
DISPLAY INVISIBLE (-6425 2700);
FORCEADD Q_CAP..1
(-3025 4200);
FORCEPROP 1 LAST LOCATION C560
J 0
(-2975 4300);
DISPLAY 0.978723 (-2975 4300);
PAINT WHITE (-2975 4300);
FORCEPROP 0 LAST $SEC 1
J 0
(-2975 4350);
DISPLAY 0.680851 (-2975 4350);
PAINT MONO (-2975 4350);
DISPLAY INVISIBLE (-2975 4350);
FORCEPROP 0 LAST CDS_SEC 1
J 0
(-2975 4350);
DISPLAY 0.680851 (-2975 4350);
DISPLAY INVISIBLE (-2975 4350);
FORCEPROP 1 LASTPIN (-3025 4300) $PN 1
J 0
(-3015 4280);
DISPLAY 0.787234 (-3015 4280);
PAINT MONO (-3015 4280);
FORCEPROP 1 LASTPIN (-3025 4100) $PN 2
J 0
(-3015 4080);
DISPLAY 0.787234 (-3015 4080);
PAINT MONO (-3015 4080);
FORCEPROP 1 LAST PACK_TYPE C0805
J 0
(-2975 4050);
DISPLAY 0.510638 (-2975 4050);
FORCEPROP 1 LAST TOLERANCE 20%
J 0
(-2975 4150);
DISPLAY 0.510638 (-2975 4150);
FORCEPROP 1 LAST VALUE 100UF
J 0
(-2975 4250);
DISPLAY 0.510638 (-2975 4250);
FORCEPROP 1 LAST MATERIAL X6S
J 0
(-2975 4100);
DISPLAY 0.510638 (-2975 4100);
FORCEPROP 1 LAST VOLTAGE 4V
J 0
(-2975 4200);
DISPLAY 0.510638 (-2975 4200);
FORCEPROP 2 LAST CDS_LIB pure_quanta
J 0
(-3025 4200);
DISPLAY INVISIBLE (-3025 4200);
FORCEPROP 1 LAST PATH I70
J 0
(-2975 4350);
DISPLAY 0.978723 (-2975 4350);
PAINT WHITE (-2975 4350);
DISPLAY INVISIBLE (-2975 4350);
FORCEPROP 1 LAST PART_NUMBER CH710KMEA01
J 0
(-2975 4050);
DISPLAY 0.404255 (-2975 4050);
DISPLAY INVISIBLE (-2975 4050);
FORCEADD Q_CAP..1
(-2800 4200);
FORCEPROP 1 LAST LOCATION C564
J 0
(-2750 4300);
DISPLAY 0.978723 (-2750 4300);
PAINT WHITE (-2750 4300);
FORCEPROP 0 LAST $SEC 1
J 0
(-2750 4350);
DISPLAY 0.680851 (-2750 4350);
PAINT MONO (-2750 4350);
DISPLAY INVISIBLE (-2750 4350);
FORCEPROP 0 LAST CDS_SEC 1
J 0
(-2750 4350);
DISPLAY 0.680851 (-2750 4350);
DISPLAY INVISIBLE (-2750 4350);
FORCEPROP 1 LASTPIN (-2800 4300) $PN 1
J 0
(-2790 4280);
DISPLAY 0.787234 (-2790 4280);
PAINT MONO (-2790 4280);
FORCEPROP 1 LASTPIN (-2800 4100) $PN 2
J 0
(-2790 4080);
DISPLAY 0.787234 (-2790 4080);
PAINT MONO (-2790 4080);
FORCEPROP 1 LAST VALUE 100UF
J 0
(-2750 4250);
DISPLAY 0.510638 (-2750 4250);
FORCEPROP 1 LAST VOLTAGE 4V
J 0
(-2750 4200);
DISPLAY 0.510638 (-2750 4200);
FORCEPROP 1 LAST TOLERANCE 20%
J 0
(-2750 4150);
DISPLAY 0.510638 (-2750 4150);
FORCEPROP 1 LAST MATERIAL X6S
J 0
(-2750 4100);
DISPLAY 0.510638 (-2750 4100);
FORCEPROP 1 LAST PACK_TYPE C0805
J 0
(-2750 4050);
DISPLAY 0.510638 (-2750 4050);
FORCEPROP 2 LAST CDS_LIB pure_quanta
J 0
(-2800 4200);
DISPLAY INVISIBLE (-2800 4200);
FORCEPROP 1 LAST PATH I71
J 0
(-2750 4350);
DISPLAY 0.978723 (-2750 4350);
PAINT WHITE (-2750 4350);
DISPLAY INVISIBLE (-2750 4350);
FORCEPROP 1 LAST PART_NUMBER CH710KMEA01
J 0
(-2750 4050);
DISPLAY 0.404255 (-2750 4050);
DISPLAY INVISIBLE (-2750 4050);
FORCEADD Q_CAP..1
(-4100 5475);
FORCEPROP 1 LAST LOCATION C559
J 0
(-4050 5575);
DISPLAY 0.978723 (-4050 5575);
PAINT WHITE (-4050 5575);
FORCEPROP 0 LAST $SEC 1
J 0
(-4050 5625);
DISPLAY 0.680851 (-4050 5625);
PAINT MONO (-4050 5625);
DISPLAY INVISIBLE (-4050 5625);
FORCEPROP 0 LAST CDS_SEC 1
J 0
(-4050 5625);
DISPLAY 0.680851 (-4050 5625);
DISPLAY INVISIBLE (-4050 5625);
FORCEPROP 1 LASTPIN (-4100 5575) $PN 1
J 0
(-4090 5555);
DISPLAY 0.787234 (-4090 5555);
PAINT MONO (-4090 5555);
FORCEPROP 1 LASTPIN (-4100 5375) $PN 2
J 0
(-4090 5355);
DISPLAY 0.787234 (-4090 5355);
PAINT MONO (-4090 5355);
FORCEPROP 1 LAST VALUE 100UF
J 0
(-4050 5525);
DISPLAY 0.510638 (-4050 5525);
FORCEPROP 1 LAST VOLTAGE 4V
J 0
(-4050 5475);
DISPLAY 0.510638 (-4050 5475);
FORCEPROP 1 LAST TOLERANCE 20%
J 0
(-4050 5425);
DISPLAY 0.510638 (-4050 5425);
FORCEPROP 1 LAST PACK_TYPE C0805
J 0
(-4050 5325);
DISPLAY 0.510638 (-4050 5325);
FORCEPROP 1 LAST MATERIAL X6S
J 0
(-4050 5375);
DISPLAY 0.510638 (-4050 5375);
FORCEPROP 2 LAST CDS_LIB pure_quanta
J 0
(-4100 5475);
DISPLAY INVISIBLE (-4100 5475);
FORCEPROP 1 LAST PATH I72
J 0
(-4050 5625);
DISPLAY 0.978723 (-4050 5625);
PAINT WHITE (-4050 5625);
DISPLAY INVISIBLE (-4050 5625);
FORCEPROP 1 LAST PART_NUMBER CH710KMEA01
J 0
(-4050 5325);
DISPLAY 0.404255 (-4050 5325);
DISPLAY INVISIBLE (-4050 5325);
FORCEADD Q_CAP..1
(-3525 5450);
FORCEPROP 1 LAST LOCATION C574
J 0
(-3475 5550);
DISPLAY 0.978723 (-3475 5550);
PAINT WHITE (-3475 5550);
FORCEPROP 0 LAST $SEC 1
J 0
(-3475 5600);
DISPLAY 0.680851 (-3475 5600);
PAINT MONO (-3475 5600);
DISPLAY INVISIBLE (-3475 5600);
FORCEPROP 0 LAST CDS_SEC 1
J 0
(-3475 5600);
DISPLAY 0.680851 (-3475 5600);
DISPLAY INVISIBLE (-3475 5600);
FORCEPROP 1 LASTPIN (-3525 5550) $PN 1
J 0
(-3515 5530);
DISPLAY 0.787234 (-3515 5530);
PAINT MONO (-3515 5530);
FORCEPROP 1 LASTPIN (-3525 5350) $PN 2
J 0
(-3515 5330);
DISPLAY 0.787234 (-3515 5330);
PAINT MONO (-3515 5330);
FORCEPROP 1 LAST TOLERANCE 20%
J 0
(-3475 5400);
DISPLAY 0.510638 (-3475 5400);
FORCEPROP 1 LAST PACK_TYPE C0402
J 0
(-3475 5300);
DISPLAY 0.510638 (-3475 5300);
FORCEPROP 1 LAST MATERIAL X6S
J 0
(-3475 5350);
DISPLAY 0.510638 (-3475 5350);
FORCEPROP 1 LAST VOLTAGE 6.3V
J 0
(-3475 5450);
DISPLAY 0.510638 (-3475 5450);
FORCEPROP 1 LAST VALUE 10UF
J 0
(-3475 5500);
DISPLAY 0.510638 (-3475 5500);
FORCEPROP 2 LAST CDS_LIB pure_quanta
J 0
(-3525 5450);
DISPLAY INVISIBLE (-3525 5450);
FORCEPROP 1 LAST PATH I73
J 0
(-3475 5600);
DISPLAY 0.978723 (-3475 5600);
PAINT WHITE (-3475 5600);
DISPLAY INVISIBLE (-3475 5600);
FORCEPROP 1 LAST PART_NUMBER CH6101MEB01
J 0
(-3475 5300);
DISPLAY 0.978723 (-3475 5300);
DISPLAY INVISIBLE (-3475 5300);
FORCEADD Q_CAP..1
(-3825 5475);
FORCEPROP 1 LAST LOCATION C563
J 0
(-3775 5575);
DISPLAY 0.978723 (-3775 5575);
PAINT WHITE (-3775 5575);
FORCEPROP 0 LAST $SEC 1
J 0
(-3775 5625);
DISPLAY 0.680851 (-3775 5625);
PAINT MONO (-3775 5625);
DISPLAY INVISIBLE (-3775 5625);
FORCEPROP 0 LAST CDS_SEC 1
J 0
(-3775 5625);
DISPLAY 0.680851 (-3775 5625);
DISPLAY INVISIBLE (-3775 5625);
FORCEPROP 1 LASTPIN (-3825 5575) $PN 1
J 0
(-3815 5555);
DISPLAY 0.787234 (-3815 5555);
PAINT MONO (-3815 5555);
FORCEPROP 1 LASTPIN (-3825 5375) $PN 2
J 0
(-3815 5355);
DISPLAY 0.787234 (-3815 5355);
PAINT MONO (-3815 5355);
FORCEPROP 1 LAST PACK_TYPE C0402
J 0
(-3775 5325);
DISPLAY 0.510638 (-3775 5325);
FORCEPROP 1 LAST MATERIAL X6S
J 0
(-3775 5375);
DISPLAY 0.510638 (-3775 5375);
FORCEPROP 1 LAST TOLERANCE 20%
J 0
(-3775 5425);
DISPLAY 0.510638 (-3775 5425);
FORCEPROP 1 LAST VOLTAGE 4V
J 0
(-3775 5475);
DISPLAY 0.510638 (-3775 5475);
FORCEPROP 1 LAST VALUE 22UF
J 0
(-3775 5525);
DISPLAY 0.510638 (-3775 5525);
FORCEPROP 2 LAST CDS_LIB pure_quanta
J 0
(-3825 5475);
DISPLAY INVISIBLE (-3825 5475);
FORCEPROP 1 LAST PATH I74
J 0
(-3775 5625);
DISPLAY 0.978723 (-3775 5625);
PAINT WHITE (-3775 5625);
DISPLAY INVISIBLE (-3775 5625);
FORCEPROP 1 LAST PART_NUMBER CH622KMEB02
J 0
(-3775 5325);
DISPLAY 0.978723 (-3775 5325);
DISPLAY INVISIBLE (-3775 5325);
FORCEADD Q_CAP..1
(-2550 4200);
FORCEPROP 1 LAST LOCATION C586
J 0
(-2500 4300);
DISPLAY 0.978723 (-2500 4300);
PAINT WHITE (-2500 4300);
FORCEPROP 0 LAST $SEC 1
J 0
(-2500 4350);
DISPLAY 0.680851 (-2500 4350);
PAINT MONO (-2500 4350);
DISPLAY INVISIBLE (-2500 4350);
FORCEPROP 0 LAST CDS_SEC 1
J 0
(-2500 4350);
DISPLAY 0.680851 (-2500 4350);
DISPLAY INVISIBLE (-2500 4350);
FORCEPROP 1 LASTPIN (-2550 4300) $PN 1
J 0
(-2540 4280);
DISPLAY 0.787234 (-2540 4280);
PAINT MONO (-2540 4280);
FORCEPROP 1 LASTPIN (-2550 4100) $PN 2
J 0
(-2540 4080);
DISPLAY 0.787234 (-2540 4080);
PAINT MONO (-2540 4080);
FORCEPROP 1 LAST VALUE 22UF
J 0
(-2500 4250);
DISPLAY 0.510638 (-2500 4250);
FORCEPROP 1 LAST TOLERANCE 20%
J 0
(-2500 4150);
DISPLAY 0.510638 (-2500 4150);
FORCEPROP 1 LAST PACK_TYPE C0402
J 0
(-2500 4050);
DISPLAY 0.510638 (-2500 4050);
FORCEPROP 1 LAST MATERIAL X6S
J 0
(-2500 4100);
DISPLAY 0.510638 (-2500 4100);
FORCEPROP 1 LAST VOLTAGE 4V
J 0
(-2500 4200);
DISPLAY 0.510638 (-2500 4200);
FORCEPROP 2 LAST CDS_LIB pure_quanta
J 0
(-2550 4200);
DISPLAY INVISIBLE (-2550 4200);
FORCEPROP 1 LAST PATH I75
J 0
(-2500 4350);
DISPLAY 0.978723 (-2500 4350);
PAINT WHITE (-2500 4350);
DISPLAY INVISIBLE (-2500 4350);
FORCEPROP 1 LAST PART_NUMBER CH622KMEB02
J 0
(-2500 4050);
DISPLAY 0.978723 (-2500 4050);
DISPLAY INVISIBLE (-2500 4050);
FORCEADD Q_CAP..1
(-2325 4200);
FORCEPROP 1 LAST LOCATION C565
J 0
(-2275 4300);
DISPLAY 0.978723 (-2275 4300);
PAINT WHITE (-2275 4300);
FORCEPROP 0 LAST $SEC 1
J 0
(-2275 4350);
DISPLAY 0.680851 (-2275 4350);
PAINT MONO (-2275 4350);
DISPLAY INVISIBLE (-2275 4350);
FORCEPROP 0 LAST CDS_SEC 1
J 0
(-2275 4350);
DISPLAY 0.680851 (-2275 4350);
DISPLAY INVISIBLE (-2275 4350);
FORCEPROP 1 LASTPIN (-2325 4300) $PN 1
J 0
(-2315 4280);
DISPLAY 0.787234 (-2315 4280);
PAINT MONO (-2315 4280);
FORCEPROP 1 LASTPIN (-2325 4100) $PN 2
J 0
(-2315 4080);
DISPLAY 0.787234 (-2315 4080);
PAINT MONO (-2315 4080);
FORCEPROP 1 LAST PACK_TYPE C0402
J 0
(-2275 4050);
DISPLAY 0.510638 (-2275 4050);
FORCEPROP 1 LAST VALUE 22UF
J 0
(-2275 4250);
DISPLAY 0.510638 (-2275 4250);
FORCEPROP 1 LAST VOLTAGE 4V
J 0
(-2275 4200);
DISPLAY 0.510638 (-2275 4200);
FORCEPROP 1 LAST MATERIAL X6S
J 0
(-2275 4100);
DISPLAY 0.510638 (-2275 4100);
FORCEPROP 1 LAST TOLERANCE 20%
J 0
(-2275 4150);
DISPLAY 0.510638 (-2275 4150);
FORCEPROP 2 LAST CDS_LIB pure_quanta
J 0
(-2325 4200);
DISPLAY INVISIBLE (-2325 4200);
FORCEPROP 1 LAST PATH I76
J 0
(-2275 4350);
DISPLAY 0.978723 (-2275 4350);
PAINT WHITE (-2275 4350);
DISPLAY INVISIBLE (-2275 4350);
FORCEPROP 1 LAST PART_NUMBER CH622KMEB02
J 0
(-2275 4050);
DISPLAY 0.978723 (-2275 4050);
DISPLAY INVISIBLE (-2275 4050);
FORCEADD Q_CAP..1
(-2100 4200);
FORCEPROP 1 LAST LOCATION C575
J 0
(-2050 4300);
DISPLAY 0.978723 (-2050 4300);
PAINT WHITE (-2050 4300);
FORCEPROP 0 LAST $SEC 1
J 0
(-2050 4350);
DISPLAY 0.680851 (-2050 4350);
PAINT MONO (-2050 4350);
DISPLAY INVISIBLE (-2050 4350);
FORCEPROP 0 LAST CDS_SEC 1
J 0
(-2050 4350);
DISPLAY 0.680851 (-2050 4350);
DISPLAY INVISIBLE (-2050 4350);
FORCEPROP 1 LASTPIN (-2100 4300) $PN 1
J 0
(-2090 4280);
DISPLAY 0.787234 (-2090 4280);
PAINT MONO (-2090 4280);
FORCEPROP 1 LASTPIN (-2100 4100) $PN 2
J 0
(-2090 4080);
DISPLAY 0.787234 (-2090 4080);
PAINT MONO (-2090 4080);
FORCEPROP 1 LAST VOLTAGE 4V
J 0
(-2050 4200);
DISPLAY 0.510638 (-2050 4200);
FORCEPROP 1 LAST VALUE 22UF
J 0
(-2050 4250);
DISPLAY 0.510638 (-2050 4250);
FORCEPROP 1 LAST PACK_TYPE C0402
J 0
(-2050 4050);
DISPLAY 0.510638 (-2050 4050);
FORCEPROP 1 LAST MATERIAL X6S
J 0
(-2050 4100);
DISPLAY 0.510638 (-2050 4100);
FORCEPROP 1 LAST TOLERANCE 20%
J 0
(-2050 4150);
DISPLAY 0.510638 (-2050 4150);
FORCEPROP 2 LAST CDS_LIB pure_quanta
J 0
(-2100 4200);
DISPLAY INVISIBLE (-2100 4200);
FORCEPROP 1 LAST PATH I77
J 0
(-2050 4350);
DISPLAY 0.978723 (-2050 4350);
PAINT WHITE (-2050 4350);
DISPLAY INVISIBLE (-2050 4350);
FORCEPROP 1 LAST PART_NUMBER CH622KMEB02
J 0
(-2050 4050);
DISPLAY 0.978723 (-2050 4050);
DISPLAY INVISIBLE (-2050 4050);
FORCEADD Q_CAP..1
(-1875 4200);
FORCEPROP 1 LAST LOCATION C568
J 0
(-1825 4300);
DISPLAY 0.978723 (-1825 4300);
PAINT WHITE (-1825 4300);
FORCEPROP 0 LAST $SEC 1
J 0
(-1825 4350);
DISPLAY 0.680851 (-1825 4350);
PAINT MONO (-1825 4350);
DISPLAY INVISIBLE (-1825 4350);
FORCEPROP 0 LAST CDS_SEC 1
J 0
(-1825 4350);
DISPLAY 0.680851 (-1825 4350);
DISPLAY INVISIBLE (-1825 4350);
FORCEPROP 1 LASTPIN (-1875 4300) $PN 1
J 0
(-1865 4280);
DISPLAY 0.787234 (-1865 4280);
PAINT MONO (-1865 4280);
FORCEPROP 1 LASTPIN (-1875 4100) $PN 2
J 0
(-1865 4080);
DISPLAY 0.787234 (-1865 4080);
PAINT MONO (-1865 4080);
FORCEPROP 1 LAST VALUE 22UF
J 0
(-1825 4250);
DISPLAY 0.510638 (-1825 4250);
FORCEPROP 1 LAST PACK_TYPE C0402
J 0
(-1825 4050);
DISPLAY 0.510638 (-1825 4050);
FORCEPROP 1 LAST MATERIAL X6S
J 0
(-1825 4100);
DISPLAY 0.510638 (-1825 4100);
FORCEPROP 1 LAST VOLTAGE 4V
J 0
(-1825 4200);
DISPLAY 0.510638 (-1825 4200);
FORCEPROP 1 LAST TOLERANCE 20%
J 0
(-1825 4150);
DISPLAY 0.510638 (-1825 4150);
FORCEPROP 2 LAST CDS_LIB pure_quanta
J 0
(-1875 4200);
DISPLAY INVISIBLE (-1875 4200);
FORCEPROP 1 LAST PATH I78
J 0
(-1825 4350);
DISPLAY 0.978723 (-1825 4350);
PAINT WHITE (-1825 4350);
DISPLAY INVISIBLE (-1825 4350);
FORCEPROP 1 LAST PART_NUMBER CH622KMEB02
J 0
(-1825 4050);
DISPLAY 0.978723 (-1825 4050);
DISPLAY INVISIBLE (-1825 4050);
FORCEADD Q_CAP..1
(-3250 5450);
FORCEPROP 1 LAST LOCATION C569
J 0
(-3200 5550);
DISPLAY 0.978723 (-3200 5550);
PAINT WHITE (-3200 5550);
FORCEPROP 0 LAST $SEC 1
J 0
(-3200 5600);
DISPLAY 0.680851 (-3200 5600);
PAINT MONO (-3200 5600);
DISPLAY INVISIBLE (-3200 5600);
FORCEPROP 0 LAST CDS_SEC 1
J 0
(-3200 5600);
DISPLAY 0.680851 (-3200 5600);
DISPLAY INVISIBLE (-3200 5600);
FORCEPROP 1 LASTPIN (-3250 5550) $PN 1
J 0
(-3240 5530);
DISPLAY 0.787234 (-3240 5530);
PAINT MONO (-3240 5530);
FORCEPROP 1 LASTPIN (-3250 5350) $PN 2
J 0
(-3240 5330);
DISPLAY 0.787234 (-3240 5330);
PAINT MONO (-3240 5330);
FORCEPROP 1 LAST MATERIAL X6S
J 0
(-3200 5350);
DISPLAY 0.510638 (-3200 5350);
FORCEPROP 1 LAST PACK_TYPE 0402
J 0
(-3200 5300);
DISPLAY 0.510638 (-3200 5300);
FORCEPROP 1 LAST VALUE 4.7UF
J 0
(-3200 5500);
DISPLAY 0.510638 (-3200 5500);
FORCEPROP 1 LAST TOLERANCE 20%
J 0
(-3200 5400);
DISPLAY 0.510638 (-3200 5400);
FORCEPROP 1 LAST VOLTAGE 6.3V
J 0
(-3200 5450);
DISPLAY 0.510638 (-3200 5450);
FORCEPROP 2 LAST CDS_LIB pure_quanta
J 0
(-3250 5450);
DISPLAY INVISIBLE (-3250 5450);
FORCEPROP 1 LAST PATH I79
J 0
(-3200 5600);
DISPLAY 0.978723 (-3200 5600);
PAINT WHITE (-3200 5600);
DISPLAY INVISIBLE (-3200 5600);
FORCEPROP 1 LAST PART_NUMBER CH5471MEB01
J 0
(-3200 5300);
DISPLAY 0.978723 (-3200 5300);
DISPLAY INVISIBLE (-3200 5300);
FORCEADD Q_CAP..1
(-6775 3125);
FORCEPROP 1 LAST LOCATION C513
J 0
(-6725 3225);
DISPLAY 0.638298 (-6725 3225);
PAINT WHITE (-6725 3225);
FORCEPROP 0 LAST $SEC 1
J 0
(-6725 3275);
DISPLAY 0.680851 (-6725 3275);
PAINT MONO (-6725 3275);
DISPLAY INVISIBLE (-6725 3275);
FORCEPROP 0 LAST CDS_SEC 1
J 0
(-6725 3275);
DISPLAY 0.680851 (-6725 3275);
DISPLAY INVISIBLE (-6725 3275);
FORCEPROP 1 LASTPIN (-6775 3225) $PN 1
J 0
(-6765 3205);
DISPLAY 0.787234 (-6765 3205);
PAINT MONO (-6765 3205);
FORCEPROP 1 LASTPIN (-6775 3025) $PN 2
J 0
(-6765 3005);
DISPLAY 0.787234 (-6765 3005);
PAINT MONO (-6765 3005);
FORCEPROP 1 LAST PACK_TYPE 0201
J 0
(-6725 2975);
DISPLAY 0.510638 (-6725 2975);
FORCEPROP 1 LAST TOLERANCE 20%
J 0
(-6725 3075);
DISPLAY 0.510638 (-6725 3075);
FORCEPROP 1 LAST VOLTAGE 4V
J 0
(-6725 3125);
DISPLAY 0.510638 (-6725 3125);
FORCEPROP 1 LAST VALUE 1UF
J 0
(-6725 3175);
DISPLAY 0.510638 (-6725 3175);
FORCEPROP 1 LAST MATERIAL X6S
J 0
(-6725 3025);
DISPLAY 0.510638 (-6725 3025);
FORCEPROP 2 LAST CDS_LIB pure_quanta
J 0
(-6775 3125);
DISPLAY INVISIBLE (-6775 3125);
FORCEPROP 1 LAST PATH I8
J 0
(-6725 3275);
DISPLAY 0.978723 (-6725 3275);
PAINT WHITE (-6725 3275);
DISPLAY INVISIBLE (-6725 3275);
FORCEPROP 1 LAST PART_NUMBER CH-10KMEE00
J 0
(-6725 2975);
DISPLAY 0.510638 (-6725 2975);
DISPLAY INVISIBLE (-6725 2975);
FORCEADD Q_CAP..1
(-2950 5450);
FORCEPROP 1 LAST LOCATION C528
J 0
(-2900 5550);
DISPLAY 0.978723 (-2900 5550);
PAINT WHITE (-2900 5550);
FORCEPROP 0 LAST $SEC 1
J 0
(-2900 5600);
DISPLAY 0.680851 (-2900 5600);
PAINT MONO (-2900 5600);
DISPLAY INVISIBLE (-2900 5600);
FORCEPROP 0 LAST CDS_SEC 1
J 0
(-2900 5600);
DISPLAY 0.680851 (-2900 5600);
DISPLAY INVISIBLE (-2900 5600);
FORCEPROP 1 LASTPIN (-2950 5550) $PN 1
J 0
(-2940 5530);
DISPLAY 0.787234 (-2940 5530);
PAINT MONO (-2940 5530);
FORCEPROP 1 LASTPIN (-2950 5350) $PN 2
J 0
(-2940 5330);
DISPLAY 0.787234 (-2940 5330);
PAINT MONO (-2940 5330);
FORCEPROP 1 LAST MATERIAL X6S
J 0
(-2900 5350);
DISPLAY 0.510638 (-2900 5350);
FORCEPROP 1 LAST VOLTAGE 4V
J 0
(-2900 5450);
DISPLAY 0.510638 (-2900 5450);
FORCEPROP 1 LAST TOLERANCE 20%
J 0
(-2900 5400);
DISPLAY 0.510638 (-2900 5400);
FORCEPROP 1 LAST VALUE 1UF
J 0
(-2900 5500);
DISPLAY 0.510638 (-2900 5500);
FORCEPROP 1 LAST PACK_TYPE 0201
J 0
(-2900 5300);
DISPLAY 0.510638 (-2900 5300);
FORCEPROP 2 LAST CDS_LIB pure_quanta
J 0
(-2950 5450);
DISPLAY INVISIBLE (-2950 5450);
FORCEPROP 1 LAST PATH I80
J 0
(-2900 5600);
DISPLAY 0.978723 (-2900 5600);
PAINT WHITE (-2900 5600);
DISPLAY INVISIBLE (-2900 5600);
FORCEPROP 1 LAST PART_NUMBER CH-10KMEE00
J 0
(-2900 5300);
DISPLAY 0.510638 (-2900 5300);
DISPLAY INVISIBLE (-2900 5300);
FORCEADD Q_CAP..1
(-2675 5450);
FORCEPROP 1 LAST LOCATION C522
J 0
(-2625 5550);
DISPLAY 0.978723 (-2625 5550);
PAINT WHITE (-2625 5550);
FORCEPROP 0 LAST $SEC 1
J 0
(-2625 5600);
DISPLAY 0.680851 (-2625 5600);
PAINT MONO (-2625 5600);
DISPLAY INVISIBLE (-2625 5600);
FORCEPROP 0 LAST CDS_SEC 1
J 0
(-2625 5600);
DISPLAY 0.680851 (-2625 5600);
DISPLAY INVISIBLE (-2625 5600);
FORCEPROP 1 LASTPIN (-2675 5550) $PN 1
J 0
(-2665 5530);
DISPLAY 0.787234 (-2665 5530);
PAINT MONO (-2665 5530);
FORCEPROP 1 LASTPIN (-2675 5350) $PN 2
J 0
(-2665 5330);
DISPLAY 0.787234 (-2665 5330);
PAINT MONO (-2665 5330);
FORCEPROP 1 LAST VALUE 0.1UF
J 0
(-2625 5500);
DISPLAY 0.638298 (-2625 5500);
FORCEPROP 1 LAST MATERIAL X7S
J 0
(-2625 5350);
DISPLAY 0.638298 (-2625 5350);
FORCEPROP 1 LAST VOLTAGE 10V
J 0
(-2625 5450);
DISPLAY 0.638298 (-2625 5450);
FORCEPROP 1 LAST TOLERANCE 10%
J 0
(-2625 5400);
DISPLAY 0.638298 (-2625 5400);
FORCEPROP 1 LAST PACK_TYPE C0201
J 0
(-2625 5300);
DISPLAY 0.638298 (-2625 5300);
FORCEPROP 2 LAST CDS_LIB pure_quanta
J 0
(-2675 5450);
DISPLAY INVISIBLE (-2675 5450);
FORCEPROP 1 LAST PATH I81
J 0
(-2625 5600);
DISPLAY 0.978723 (-2625 5600);
PAINT WHITE (-2625 5600);
DISPLAY INVISIBLE (-2625 5600);
FORCEPROP 1 LAST PART_NUMBER CH4102K6E00
J 0
(-2625 5300);
DISPLAY 0.978723 (-2625 5300);
DISPLAY INVISIBLE (-2625 5300);
FORCEADD Q_CAP..1
(-1575 4200);
FORCEPROP 1 LAST LOCATION C584
J 0
(-1525 4300);
DISPLAY 0.978723 (-1525 4300);
PAINT WHITE (-1525 4300);
FORCEPROP 0 LAST $SEC 1
J 0
(-1525 4350);
DISPLAY 0.680851 (-1525 4350);
PAINT MONO (-1525 4350);
DISPLAY INVISIBLE (-1525 4350);
FORCEPROP 0 LAST CDS_SEC 1
J 0
(-1525 4350);
DISPLAY 0.680851 (-1525 4350);
DISPLAY INVISIBLE (-1525 4350);
FORCEPROP 1 LASTPIN (-1575 4300) $PN 1
J 0
(-1565 4280);
DISPLAY 0.787234 (-1565 4280);
PAINT MONO (-1565 4280);
FORCEPROP 1 LASTPIN (-1575 4100) $PN 2
J 0
(-1565 4080);
DISPLAY 0.787234 (-1565 4080);
PAINT MONO (-1565 4080);
FORCEPROP 1 LAST PACK_TYPE C0402
J 0
(-1525 4050);
DISPLAY 0.510638 (-1525 4050);
FORCEPROP 1 LAST VALUE 10UF
J 0
(-1525 4250);
DISPLAY 0.510638 (-1525 4250);
FORCEPROP 1 LAST VOLTAGE 6.3V
J 0
(-1525 4200);
DISPLAY 0.510638 (-1525 4200);
FORCEPROP 1 LAST TOLERANCE 20%
J 0
(-1525 4150);
DISPLAY 0.510638 (-1525 4150);
FORCEPROP 1 LAST MATERIAL X6S
J 0
(-1525 4100);
DISPLAY 0.510638 (-1525 4100);
FORCEPROP 2 LAST CDS_LIB pure_quanta
J 0
(-1575 4200);
DISPLAY INVISIBLE (-1575 4200);
FORCEPROP 1 LAST PATH I82
J 0
(-1525 4350);
DISPLAY 0.978723 (-1525 4350);
PAINT WHITE (-1525 4350);
DISPLAY INVISIBLE (-1525 4350);
FORCEPROP 1 LAST PART_NUMBER CH6101MEB01
J 0
(-1525 4050);
DISPLAY 0.978723 (-1525 4050);
DISPLAY INVISIBLE (-1525 4050);
FORCEADD Q_CAP..1
(-1275 4200);
FORCEPROP 1 LAST LOCATION C567
J 0
(-1225 4300);
DISPLAY 0.978723 (-1225 4300);
PAINT WHITE (-1225 4300);
FORCEPROP 0 LAST $SEC 1
J 0
(-1225 4350);
DISPLAY 0.680851 (-1225 4350);
PAINT MONO (-1225 4350);
DISPLAY INVISIBLE (-1225 4350);
FORCEPROP 0 LAST CDS_SEC 1
J 0
(-1225 4350);
DISPLAY 0.680851 (-1225 4350);
DISPLAY INVISIBLE (-1225 4350);
FORCEPROP 1 LASTPIN (-1275 4300) $PN 1
J 0
(-1265 4280);
DISPLAY 0.787234 (-1265 4280);
PAINT MONO (-1265 4280);
FORCEPROP 1 LASTPIN (-1275 4100) $PN 2
J 0
(-1265 4080);
DISPLAY 0.787234 (-1265 4080);
PAINT MONO (-1265 4080);
FORCEPROP 1 LAST PACK_TYPE C0402
J 0
(-1225 4050);
DISPLAY 0.510638 (-1225 4050);
FORCEPROP 1 LAST TOLERANCE 20%
J 0
(-1225 4150);
DISPLAY 0.510638 (-1225 4150);
FORCEPROP 1 LAST MATERIAL X6S
J 0
(-1225 4100);
DISPLAY 0.510638 (-1225 4100);
FORCEPROP 1 LAST VOLTAGE 6.3V
J 0
(-1225 4200);
DISPLAY 0.510638 (-1225 4200);
FORCEPROP 1 LAST VALUE 10UF
J 0
(-1225 4250);
DISPLAY 0.510638 (-1225 4250);
FORCEPROP 2 LAST CDS_LIB pure_quanta
J 0
(-1275 4200);
DISPLAY INVISIBLE (-1275 4200);
FORCEPROP 1 LAST PATH I83
J 0
(-1225 4350);
DISPLAY 0.978723 (-1225 4350);
PAINT WHITE (-1225 4350);
DISPLAY INVISIBLE (-1225 4350);
FORCEPROP 1 LAST PART_NUMBER CH6101MEB01
J 0
(-1225 4050);
DISPLAY 0.978723 (-1225 4050);
DISPLAY INVISIBLE (-1225 4050);
FORCEADD Q_CAP..1
(-2325 5450);
FORCEPROP 1 LAST LOCATION C524
J 0
(-2275 5550);
DISPLAY 0.978723 (-2275 5550);
PAINT WHITE (-2275 5550);
FORCEPROP 0 LAST $SEC 1
J 0
(-2275 5600);
DISPLAY 0.680851 (-2275 5600);
PAINT MONO (-2275 5600);
DISPLAY INVISIBLE (-2275 5600);
FORCEPROP 0 LAST CDS_SEC 1
J 0
(-2275 5600);
DISPLAY 0.680851 (-2275 5600);
DISPLAY INVISIBLE (-2275 5600);
FORCEPROP 1 LASTPIN (-2325 5550) $PN 1
J 0
(-2315 5530);
DISPLAY 0.787234 (-2315 5530);
PAINT MONO (-2315 5530);
FORCEPROP 1 LASTPIN (-2325 5350) $PN 2
J 0
(-2315 5330);
DISPLAY 0.787234 (-2315 5330);
PAINT MONO (-2315 5330);
FORCEPROP 1 LAST TOLERANCE 10%
J 0
(-2275 5400);
DISPLAY 0.638298 (-2275 5400);
FORCEPROP 1 LAST MATERIAL X7S
J 0
(-2275 5350);
DISPLAY 0.638298 (-2275 5350);
FORCEPROP 1 LAST VALUE 0.1UF
J 0
(-2275 5500);
DISPLAY 0.638298 (-2275 5500);
FORCEPROP 1 LAST VOLTAGE 10V
J 0
(-2275 5450);
DISPLAY 0.638298 (-2275 5450);
FORCEPROP 1 LAST PACK_TYPE C0201
J 0
(-2275 5300);
DISPLAY 0.638298 (-2275 5300);
FORCEPROP 2 LAST CDS_LIB pure_quanta
J 0
(-2325 5450);
DISPLAY INVISIBLE (-2325 5450);
FORCEPROP 1 LAST PATH I84
J 0
(-2275 5600);
DISPLAY 0.978723 (-2275 5600);
PAINT WHITE (-2275 5600);
DISPLAY INVISIBLE (-2275 5600);
FORCEPROP 1 LAST PART_NUMBER CH4102K6E00
J 0
(-2275 5300);
DISPLAY 0.978723 (-2275 5300);
DISPLAY INVISIBLE (-2275 5300);
FORCEADD Q_CAP..1
(-2050 5450);
FORCEPROP 1 LAST LOCATION C578
J 0
(-2000 5550);
DISPLAY 0.978723 (-2000 5550);
PAINT WHITE (-2000 5550);
FORCEPROP 0 LAST $SEC 1
J 0
(-2000 5600);
DISPLAY 0.680851 (-2000 5600);
PAINT MONO (-2000 5600);
DISPLAY INVISIBLE (-2000 5600);
FORCEPROP 0 LAST CDS_SEC 1
J 0
(-2000 5600);
DISPLAY 0.680851 (-2000 5600);
DISPLAY INVISIBLE (-2000 5600);
FORCEPROP 1 LASTPIN (-2050 5550) $PN 1
J 0
(-2040 5530);
DISPLAY 0.787234 (-2040 5530);
PAINT MONO (-2040 5530);
FORCEPROP 1 LASTPIN (-2050 5350) $PN 2
J 0
(-2040 5330);
DISPLAY 0.787234 (-2040 5330);
PAINT MONO (-2040 5330);
FORCEPROP 1 LAST TOLERANCE 10%
J 0
(-2000 5400);
DISPLAY 0.638298 (-2000 5400);
FORCEPROP 1 LAST PACK_TYPE C0201
J 0
(-2000 5300);
DISPLAY 0.638298 (-2000 5300);
FORCEPROP 1 LAST MATERIAL X7S
J 0
(-2000 5350);
DISPLAY 0.638298 (-2000 5350);
FORCEPROP 1 LAST VALUE 0.1UF
J 0
(-2000 5500);
DISPLAY 0.638298 (-2000 5500);
FORCEPROP 1 LAST VOLTAGE 10V
J 0
(-2000 5450);
DISPLAY 0.638298 (-2000 5450);
FORCEPROP 2 LAST CDS_LIB pure_quanta
J 0
(-2050 5450);
DISPLAY INVISIBLE (-2050 5450);
FORCEPROP 1 LAST PATH I85
J 0
(-2000 5600);
DISPLAY 0.978723 (-2000 5600);
PAINT WHITE (-2000 5600);
DISPLAY INVISIBLE (-2000 5600);
FORCEPROP 1 LAST PART_NUMBER CH4102K6E00
J 0
(-2000 5300);
DISPLAY 0.978723 (-2000 5300);
DISPLAY INVISIBLE (-2000 5300);
FORCEADD UNIVERSAL_GND..1
(-450 4500);
FORCEPROP 3 LASTPIN (-450 4550) SIG_NAME GND\g
J 0
(-440 4560);
DISPLAY 0.659574 (-440 4560);
PAINT MONO (-440 4560);
DISPLAY INVISIBLE (-440 4560);
FORCEPROP 2 LAST CDS_LIB pure_quanta_power
J 0
(-450 4500);
DISPLAY INVISIBLE (-450 4500);
FORCEPROP 1 LAST HDL_POWER GND
J 1
(-425 4425);
DISPLAY 0.872340 (-425 4425);
PAINT GREEN (-425 4425);
DISPLAY INVISIBLE (-425 4425);
FORCEPROP 1 LAST PATH I86
J 0
(-375 4500);
DISPLAY 0.872340 (-375 4500);
PAINT AQUA (-375 4500);
DISPLAY INVISIBLE (-375 4500);
FORCEADD Q_CAP..1
(-1725 5450);
FORCEPROP 1 LAST LOCATION C540
J 0
(-1675 5550);
DISPLAY 0.978723 (-1675 5550);
PAINT WHITE (-1675 5550);
FORCEPROP 0 LAST $SEC 1
J 0
(-1675 5600);
DISPLAY 0.680851 (-1675 5600);
PAINT MONO (-1675 5600);
DISPLAY INVISIBLE (-1675 5600);
FORCEPROP 0 LAST CDS_SEC 1
J 0
(-1675 5600);
DISPLAY 0.680851 (-1675 5600);
DISPLAY INVISIBLE (-1675 5600);
FORCEPROP 1 LASTPIN (-1725 5550) $PN 1
J 0
(-1715 5530);
DISPLAY 0.787234 (-1715 5530);
PAINT MONO (-1715 5530);
FORCEPROP 1 LASTPIN (-1725 5350) $PN 2
J 0
(-1715 5330);
DISPLAY 0.787234 (-1715 5330);
PAINT MONO (-1715 5330);
FORCEPROP 1 LAST PACK_TYPE C0201
J 0
(-1675 5300);
DISPLAY 0.638298 (-1675 5300);
FORCEPROP 1 LAST MATERIAL X7S
J 0
(-1675 5350);
DISPLAY 0.638298 (-1675 5350);
FORCEPROP 1 LAST TOLERANCE 10%
J 0
(-1675 5400);
DISPLAY 0.638298 (-1675 5400);
FORCEPROP 1 LAST VALUE 0.1UF
J 0
(-1675 5500);
DISPLAY 0.638298 (-1675 5500);
FORCEPROP 1 LAST VOLTAGE 10V
J 0
(-1675 5450);
DISPLAY 0.638298 (-1675 5450);
FORCEPROP 2 LAST CDS_LIB pure_quanta
J 0
(-1725 5450);
DISPLAY INVISIBLE (-1725 5450);
FORCEPROP 1 LAST PATH I87
J 0
(-1675 5600);
DISPLAY 0.978723 (-1675 5600);
PAINT WHITE (-1675 5600);
DISPLAY INVISIBLE (-1675 5600);
FORCEPROP 1 LAST PART_NUMBER CH4102K6E00
J 0
(-1675 5300);
DISPLAY 0.978723 (-1675 5300);
DISPLAY INVISIBLE (-1675 5300);
FORCEADD Q_INDUCTOR..1
R 3
(-8225 4125);
FORCEPROP 1 LAST LOCATION L26
R 1
J 2
(-8375 4250);
DISPLAY 0.574468 (-8375 4250);
PAINT GREEN (-8375 4250);
FORCEPROP 0 LAST $SEC 1
R 1
J 0
(-8200 4250);
DISPLAY 0.680851 (-8200 4250);
PAINT MONO (-8200 4250);
DISPLAY INVISIBLE (-8200 4250);
FORCEPROP 0 LAST CDS_SEC 1
R 1
J 0
(-8200 4250);
DISPLAY 0.680851 (-8200 4250);
DISPLAY INVISIBLE (-8200 4250);
FORCEPROP 0 LASTPIN (-8200 4225) $PN 1
R 1
J 0
(-8210 4235);
DISPLAY 0.680851 (-8210 4235);
PAINT MONO (-8210 4235);
FORCEPROP 0 LASTPIN (-8200 4025) $PN 2
R 1
J 2
(-8210 4015);
DISPLAY 0.680851 (-8210 4015);
PAINT MONO (-8210 4015);
FORCEPROP 2 LAST VALUE BLM15PD121SN1D/1300MA
R 1
J 2
(-8475 4250);
DISPLAY 0.553191 (-8475 4250);
FORCEPROP 2 LAST PACK_TYPE SMLF
R 1
J 2
(-8425 4250);
DISPLAY 0.553191 (-8425 4250);
FORCEPROP 1 LAST MATERIAL IND
R 1
J 2
(-8280 4250);
DISPLAY 0.574468 (-8280 4250);
PAINT GREEN (-8280 4250);
FORCEPROP 1 LAST NEEDS_NO_SIZE TRUE
R 1
J 2
(-8225 4125);
DISPLAY 0.468085 (-8225 4125);
PAINT GREEN (-8225 4125);
DISPLAY INVISIBLE (-8225 4125);
FORCEPROP 2 LAST CDS_LIB pure_quanta
R 1
J 2
(-8225 4125);
DISPLAY INVISIBLE (-8225 4125);
FORCEPROP 1 LAST PATH I88
R 1
J 2
(-8280 4050);
DISPLAY 0.723404 (-8280 4050);
PAINT GREEN (-8280 4050);
DISPLAY INVISIBLE (-8280 4050);
FORCEPROP 1 LAST PART_NUMBER CX5PD121000
R 1
J 2
(-8325 4250);
DISPLAY 0.574468 (-8325 4250);
PAINT GREEN (-8325 4250);
DISPLAY INVISIBLE (-8325 4250);
FORCEADD Q_RES..2
(-8100 4100);
FORCEPROP 1 LAST LOCATION R960
J 0
(-8055 4225);
DISPLAY 0.808511 (-8055 4225);
FORCEPROP 0 LAST $SEC 1
J 0
(-8050 4275);
DISPLAY 0.680851 (-8050 4275);
PAINT MONO (-8050 4275);
DISPLAY INVISIBLE (-8050 4275);
FORCEPROP 0 LAST CDS_SEC 1
J 0
(-8050 4275);
DISPLAY 0.680851 (-8050 4275);
DISPLAY INVISIBLE (-8050 4275);
FORCEPROP 1 LASTPIN (-8100 4200) $PN 1
J 0
(-8095 4162);
DISPLAY 0.787234 (-8095 4162);
PAINT MONO (-8095 4162);
FORCEPROP 1 LASTPIN (-8100 4000) $PN 2
J 0
(-8095 4010);
DISPLAY 0.787234 (-8095 4010);
PAINT MONO (-8095 4010);
FORCEPROP 1 LAST MATERIAL EMPTY
J 0
(-8060 4025);
DISPLAY 0.638298 (-8060 4025);
PAINT RED (-8060 4025);
FORCEPROP 1 LAST WATTAGE 1/16W
J 0
(-8060 4075);
DISPLAY 0.638298 (-8060 4075);
FORCEPROP 1 LAST TOLERANCE 5%
J 0
(-8055 4125);
DISPLAY 0.638298 (-8055 4125);
FORCEPROP 1 LAST VALUE 0
J 0
(-8055 4175);
DISPLAY 0.638298 (-8055 4175);
FORCEPROP 1 LAST PACK_TYPE 0402LF
J 0
(-8060 3925);
DISPLAY 0.638298 (-8060 3925);
FORCEPROP 2 LAST CDS_LIB pure_quanta
J 0
(-8100 4100);
DISPLAY INVISIBLE (-8100 4100);
FORCEPROP 1 LAST PATH I89
J 0
(-8050 4275);
DISPLAY 0.978723 (-8050 4275);
PAINT WHITE (-8050 4275);
DISPLAY INVISIBLE (-8050 4275);
FORCEPROP 1 LAST PART_NUMBER CS00002JB13
J 0
(-8060 3975);
DISPLAY 0.638298 (-8060 3975);
DISPLAY INVISIBLE (-8060 3975);
FORCEADD Q_CAP..1
(-6500 3100);
FORCEPROP 1 LAST LOCATION C516
J 0
(-6450 3200);
DISPLAY 0.978723 (-6450 3200);
PAINT WHITE (-6450 3200);
FORCEPROP 0 LAST $SEC 1
J 0
(-6450 3250);
DISPLAY 0.680851 (-6450 3250);
PAINT MONO (-6450 3250);
DISPLAY INVISIBLE (-6450 3250);
FORCEPROP 0 LAST CDS_SEC 1
J 0
(-6450 3250);
DISPLAY 0.680851 (-6450 3250);
DISPLAY INVISIBLE (-6450 3250);
FORCEPROP 1 LASTPIN (-6500 3200) $PN 1
J 0
(-6490 3180);
DISPLAY 0.787234 (-6490 3180);
PAINT MONO (-6490 3180);
FORCEPROP 1 LASTPIN (-6500 3000) $PN 2
J 0
(-6490 2980);
DISPLAY 0.787234 (-6490 2980);
PAINT MONO (-6490 2980);
FORCEPROP 1 LAST PACK_TYPE C0201
J 0
(-6450 2950);
DISPLAY 0.638298 (-6450 2950);
FORCEPROP 1 LAST VALUE 0.1UF
J 0
(-6450 3150);
DISPLAY 0.638298 (-6450 3150);
FORCEPROP 1 LAST VOLTAGE 10V
J 0
(-6450 3100);
DISPLAY 0.638298 (-6450 3100);
FORCEPROP 1 LAST MATERIAL X7S
J 0
(-6450 3000);
DISPLAY 0.638298 (-6450 3000);
FORCEPROP 1 LAST TOLERANCE 10%
J 0
(-6450 3050);
DISPLAY 0.638298 (-6450 3050);
FORCEPROP 2 LAST CDS_LIB pure_quanta
J 0
(-6500 3100);
DISPLAY INVISIBLE (-6500 3100);
FORCEPROP 1 LAST PATH I9
J 0
(-6450 3250);
DISPLAY 0.978723 (-6450 3250);
PAINT WHITE (-6450 3250);
DISPLAY INVISIBLE (-6450 3250);
FORCEPROP 1 LAST PART_NUMBER CH4102K6E00
J 0
(-6450 2950);
DISPLAY 0.978723 (-6450 2950);
DISPLAY INVISIBLE (-6450 2950);
FORCEADD Q_CAP..1
(-2775 1150);
FORCEPROP 1 LAST LOCATION C542
J 0
(-2725 1250);
DISPLAY 0.978723 (-2725 1250);
PAINT WHITE (-2725 1250);
FORCEPROP 0 LAST $SEC 1
J 0
(-2725 1300);
DISPLAY 0.680851 (-2725 1300);
PAINT MONO (-2725 1300);
DISPLAY INVISIBLE (-2725 1300);
FORCEPROP 0 LAST CDS_SEC 1
J 0
(-2725 1300);
DISPLAY 0.680851 (-2725 1300);
DISPLAY INVISIBLE (-2725 1300);
FORCEPROP 1 LASTPIN (-2775 1250) $PN 1
J 0
(-2765 1230);
DISPLAY 0.787234 (-2765 1230);
PAINT MONO (-2765 1230);
FORCEPROP 1 LASTPIN (-2775 1050) $PN 2
J 0
(-2765 1030);
DISPLAY 0.787234 (-2765 1030);
PAINT MONO (-2765 1030);
FORCEPROP 1 LAST TOLERANCE 20%
J 0
(-2725 1100);
DISPLAY 0.510638 (-2725 1100);
FORCEPROP 1 LAST MATERIAL X6S
J 0
(-2725 1050);
DISPLAY 0.510638 (-2725 1050);
FORCEPROP 1 LAST VOLTAGE 4V
J 0
(-2725 1150);
DISPLAY 0.510638 (-2725 1150);
FORCEPROP 1 LAST PACK_TYPE 0201
J 0
(-2725 1000);
DISPLAY 0.510638 (-2725 1000);
FORCEPROP 1 LAST VALUE 1UF
J 0
(-2725 1200);
DISPLAY 0.510638 (-2725 1200);
FORCEPROP 2 LAST CDS_LIB pure_quanta
J 0
(-2775 1150);
DISPLAY INVISIBLE (-2775 1150);
FORCEPROP 1 LAST PATH I90
J 0
(-2725 1300);
DISPLAY 0.978723 (-2725 1300);
PAINT WHITE (-2725 1300);
DISPLAY INVISIBLE (-2725 1300);
FORCEPROP 1 LAST PART_NUMBER CH-10KMEE00
J 0
(-2725 1000);
DISPLAY 0.510638 (-2725 1000);
DISPLAY INVISIBLE (-2725 1000);
FORCEADD Q_CAP..1
(-2225 1150);
FORCEPROP 1 LAST LOCATION C545
J 0
(-2175 1250);
DISPLAY 0.978723 (-2175 1250);
PAINT WHITE (-2175 1250);
FORCEPROP 0 LAST $SEC 1
J 0
(-2175 1300);
DISPLAY 0.680851 (-2175 1300);
PAINT MONO (-2175 1300);
DISPLAY INVISIBLE (-2175 1300);
FORCEPROP 0 LAST CDS_SEC 1
J 0
(-2175 1300);
DISPLAY 0.680851 (-2175 1300);
DISPLAY INVISIBLE (-2175 1300);
FORCEPROP 1 LASTPIN (-2225 1250) $PN 1
J 0
(-2215 1230);
DISPLAY 0.787234 (-2215 1230);
PAINT MONO (-2215 1230);
FORCEPROP 1 LASTPIN (-2225 1050) $PN 2
J 0
(-2215 1030);
DISPLAY 0.787234 (-2215 1030);
PAINT MONO (-2215 1030);
FORCEPROP 1 LAST VALUE 1UF
J 0
(-2175 1200);
DISPLAY 0.510638 (-2175 1200);
FORCEPROP 1 LAST TOLERANCE 20%
J 0
(-2175 1100);
DISPLAY 0.510638 (-2175 1100);
FORCEPROP 1 LAST MATERIAL X6S
J 0
(-2175 1050);
DISPLAY 0.510638 (-2175 1050);
FORCEPROP 1 LAST PACK_TYPE 0201
J 0
(-2175 1000);
DISPLAY 0.510638 (-2175 1000);
FORCEPROP 1 LAST VOLTAGE 4V
J 0
(-2175 1150);
DISPLAY 0.510638 (-2175 1150);
FORCEPROP 2 LAST CDS_LIB pure_quanta
J 0
(-2225 1150);
DISPLAY INVISIBLE (-2225 1150);
FORCEPROP 1 LAST PATH I91
J 0
(-2175 1300);
DISPLAY 0.978723 (-2175 1300);
PAINT WHITE (-2175 1300);
DISPLAY INVISIBLE (-2175 1300);
FORCEPROP 1 LAST PART_NUMBER CH-10KMEE00
J 0
(-2175 1000);
DISPLAY 0.510638 (-2175 1000);
DISPLAY INVISIBLE (-2175 1000);
FORCEADD Q_CAP..1
(-1675 2925);
FORCEPROP 1 LAST LOCATION C583
J 0
(-1625 3025);
DISPLAY 0.978723 (-1625 3025);
PAINT WHITE (-1625 3025);
FORCEPROP 0 LAST $SEC 1
J 0
(-1625 3075);
DISPLAY 0.680851 (-1625 3075);
PAINT MONO (-1625 3075);
DISPLAY INVISIBLE (-1625 3075);
FORCEPROP 0 LAST CDS_SEC 1
J 0
(-1625 3075);
DISPLAY 0.680851 (-1625 3075);
DISPLAY INVISIBLE (-1625 3075);
FORCEPROP 1 LASTPIN (-1675 3025) $PN 1
J 0
(-1665 3005);
DISPLAY 0.787234 (-1665 3005);
PAINT MONO (-1665 3005);
FORCEPROP 1 LASTPIN (-1675 2825) $PN 2
J 0
(-1665 2805);
DISPLAY 0.787234 (-1665 2805);
PAINT MONO (-1665 2805);
FORCEPROP 1 LAST VALUE 0.1UF
J 0
(-1625 2975);
DISPLAY 0.638298 (-1625 2975);
FORCEPROP 1 LAST PACK_TYPE C0201
J 0
(-1625 2775);
DISPLAY 0.638298 (-1625 2775);
FORCEPROP 1 LAST VOLTAGE 10V
J 0
(-1625 2925);
DISPLAY 0.638298 (-1625 2925);
FORCEPROP 1 LAST TOLERANCE 10%
J 0
(-1625 2875);
DISPLAY 0.638298 (-1625 2875);
FORCEPROP 1 LAST MATERIAL X7S
J 0
(-1625 2825);
DISPLAY 0.638298 (-1625 2825);
FORCEPROP 2 LAST CDS_LIB pure_quanta
J 0
(-1675 2925);
DISPLAY INVISIBLE (-1675 2925);
FORCEPROP 1 LAST PATH I93
J 0
(-1625 3075);
DISPLAY 0.978723 (-1625 3075);
PAINT WHITE (-1625 3075);
DISPLAY INVISIBLE (-1625 3075);
FORCEPROP 1 LAST PART_NUMBER CH4102K6E00
J 0
(-1625 2775);
DISPLAY 0.978723 (-1625 2775);
DISPLAY INVISIBLE (-1625 2775);
FORCEADD Q_CAP..1
(-1375 2925);
FORCEPROP 1 LAST LOCATION C566
J 0
(-1325 3025);
DISPLAY 0.978723 (-1325 3025);
PAINT WHITE (-1325 3025);
FORCEPROP 0 LAST $SEC 1
J 0
(-1325 3075);
DISPLAY 0.680851 (-1325 3075);
PAINT MONO (-1325 3075);
DISPLAY INVISIBLE (-1325 3075);
FORCEPROP 0 LAST CDS_SEC 1
J 0
(-1325 3075);
DISPLAY 0.680851 (-1325 3075);
DISPLAY INVISIBLE (-1325 3075);
FORCEPROP 1 LASTPIN (-1375 3025) $PN 1
J 0
(-1365 3005);
DISPLAY 0.787234 (-1365 3005);
PAINT MONO (-1365 3005);
FORCEPROP 1 LASTPIN (-1375 2825) $PN 2
J 0
(-1365 2805);
DISPLAY 0.787234 (-1365 2805);
PAINT MONO (-1365 2805);
FORCEPROP 1 LAST PACK_TYPE C0201
J 0
(-1325 2775);
DISPLAY 0.638298 (-1325 2775);
FORCEPROP 1 LAST MATERIAL X7S
J 0
(-1325 2825);
DISPLAY 0.638298 (-1325 2825);
FORCEPROP 1 LAST VOLTAGE 10V
J 0
(-1325 2925);
DISPLAY 0.638298 (-1325 2925);
FORCEPROP 1 LAST TOLERANCE 10%
J 0
(-1325 2875);
DISPLAY 0.638298 (-1325 2875);
FORCEPROP 1 LAST VALUE 0.1UF
J 0
(-1325 2975);
DISPLAY 0.638298 (-1325 2975);
FORCEPROP 2 LAST CDS_LIB pure_quanta
J 0
(-1375 2925);
DISPLAY INVISIBLE (-1375 2925);
FORCEPROP 1 LAST PATH I94
J 0
(-1325 3075);
DISPLAY 0.978723 (-1325 3075);
PAINT WHITE (-1325 3075);
DISPLAY INVISIBLE (-1325 3075);
FORCEPROP 1 LAST PART_NUMBER CH4102K6E00
J 0
(-1325 2775);
DISPLAY 0.978723 (-1325 2775);
DISPLAY INVISIBLE (-1325 2775);
FORCEADD Q_CAP..1
(-450 5425);
FORCEPROP 1 LAST LOCATION C7003
J 0
(-400 5525);
DISPLAY 0.978723 (-400 5525);
FORCEPROP 0 LAST $SEC 1
J 0
(-400 5575);
DISPLAY 0.680851 (-400 5575);
PAINT MONO (-400 5575);
DISPLAY INVISIBLE (-400 5575);
FORCEPROP 0 LAST CDS_SEC 1
J 0
(-400 5575);
DISPLAY 0.680851 (-400 5575);
DISPLAY INVISIBLE (-400 5575);
FORCEPROP 1 LASTPIN (-450 5525) $PN 1
J 0
(-440 5505);
DISPLAY 0.787234 (-440 5505);
PAINT MONO (-440 5505);
FORCEPROP 1 LASTPIN (-450 5325) $PN 2
J 0
(-440 5305);
DISPLAY 0.787234 (-440 5305);
PAINT MONO (-440 5305);
FORCEPROP 1 LAST MATERIAL X6S
J 0
(-400 5325);
DISPLAY 0.638298 (-400 5325);
FORCEPROP 1 LAST TOLERANCE 20%
J 0
(-400 5375);
DISPLAY 0.638298 (-400 5375);
FORCEPROP 1 LAST VOLTAGE 4V
J 0
(-400 5425);
DISPLAY 0.638298 (-400 5425);
FORCEPROP 1 LAST VALUE 47UF
J 0
(-400 5475);
DISPLAY 0.638298 (-400 5475);
FORCEPROP 1 LAST PACK_TYPE C0805
J 0
(-400 5275);
DISPLAY 0.638298 (-400 5275);
FORCEPROP 2 LAST CDS_LIB pure_quanta
J 0
(-450 5425);
DISPLAY INVISIBLE (-450 5425);
FORCEPROP 1 LAST PATH I95
J 0
(-400 5575);
DISPLAY 0.978723 (-400 5575);
PAINT WHITE (-400 5575);
DISPLAY INVISIBLE (-400 5575);
FORCEPROP 1 LAST PART_NUMBER CH647KMEA04
J 0
(-400 5275);
DISPLAY 0.638298 (-400 5275);
DISPLAY INVISIBLE (-400 5275);
FORCEADD Q_CAP..1
(-850 5450);
FORCEPROP 1 LAST LOCATION C7002
J 0
(-800 5550);
DISPLAY 0.638298 (-800 5550);
FORCEPROP 0 LAST $SEC 1
J 0
(-800 5600);
DISPLAY 0.680851 (-800 5600);
PAINT MONO (-800 5600);
DISPLAY INVISIBLE (-800 5600);
FORCEPROP 0 LAST CDS_SEC 1
J 0
(-800 5600);
DISPLAY 0.680851 (-800 5600);
DISPLAY INVISIBLE (-800 5600);
FORCEPROP 1 LASTPIN (-850 5550) $PN 1
J 0
(-840 5530);
DISPLAY 0.787234 (-840 5530);
PAINT MONO (-840 5530);
FORCEPROP 1 LASTPIN (-850 5350) $PN 2
J 0
(-840 5330);
DISPLAY 0.787234 (-840 5330);
PAINT MONO (-840 5330);
FORCEPROP 1 LAST PACK_TYPE C0805
J 0
(-800 5250);
DISPLAY 0.638298 (-800 5250);
FORCEPROP 1 LAST MATERIAL X6S
J 0
(-800 5350);
DISPLAY 0.638298 (-800 5350);
FORCEPROP 1 LAST VALUE 47UF
J 0
(-800 5500);
DISPLAY 0.638298 (-800 5500);
FORCEPROP 1 LAST VOLTAGE 4V
J 0
(-800 5450);
DISPLAY 0.638298 (-800 5450);
FORCEPROP 1 LAST TOLERANCE 20%
J 0
(-800 5400);
DISPLAY 0.638298 (-800 5400);
FORCEPROP 2 LAST CDS_LIB pure_quanta
J 0
(-850 5450);
DISPLAY INVISIBLE (-850 5450);
FORCEPROP 1 LAST PATH I96
J 0
(-800 5600);
DISPLAY 0.978723 (-800 5600);
PAINT WHITE (-800 5600);
DISPLAY INVISIBLE (-800 5600);
FORCEPROP 1 LAST PART_NUMBER CH647KMEA04
J 0
(-800 5300);
DISPLAY 0.638298 (-800 5300);
DISPLAY INVISIBLE (-800 5300);
FORCEADD Q_CAPP..1
(-1150 5450);
FORCEPROP 1 LAST LOCATION C7001
J 0
(-1100 5550);
DISPLAY 0.787234 (-1100 5550);
FORCEPROP 0 LAST $SEC 1
J 0
(-1100 5600);
DISPLAY 0.680851 (-1100 5600);
PAINT MONO (-1100 5600);
DISPLAY INVISIBLE (-1100 5600);
FORCEPROP 0 LAST CDS_SEC 1
J 0
(-1100 5600);
DISPLAY 0.680851 (-1100 5600);
DISPLAY INVISIBLE (-1100 5600);
FORCEPROP 1 LASTPIN (-1150 5550) $PN 1
J 0
(-1140 5535);
DISPLAY 0.787234 (-1140 5535);
PAINT MONO (-1140 5535);
FORCEPROP 1 LASTPIN (-1150 5350) $PN 2
J 0
(-1140 5335);
DISPLAY 0.787234 (-1140 5335);
PAINT MONO (-1140 5335);
FORCEPROP 1 LAST TOLERANCE 20%
J 0
(-1100 5450);
DISPLAY 0.510638 (-1100 5450);
FORCEPROP 1 LAST VALUE 470UF
J 0
(-1100 5500);
DISPLAY 0.510638 (-1100 5500);
FORCEPROP 1 LAST PACK_TYPE SMLF
J 0
(-1100 5300);
DISPLAY 0.510638 (-1100 5300);
FORCEPROP 1 LAST MATERIAL SPCAP
J 0
(-1100 5350);
DISPLAY 0.510638 (-1100 5350);
FORCEPROP 1 LAST VOLTAGE 2.5V
J 0
(-1100 5400);
DISPLAY 0.510638 (-1100 5400);
FORCEPROP 2 LAST CDS_LIB pure_quanta
J 0
(-1150 5450);
DISPLAY INVISIBLE (-1150 5450);
FORCEPROP 1 LAST PATH I97
J 0
(-1100 5600);
DISPLAY 0.978723 (-1100 5600);
DISPLAY INVISIBLE (-1100 5600);
FORCEPROP 1 LAST PART_NUMBER CH747LM8818
J 0
(-1100 5250);
DISPLAY 0.404255 (-1100 5250);
DISPLAY INVISIBLE (-1100 5250);
FORCEADD Q_CAPP..1
(-1450 5450);
FORCEPROP 1 LAST LOCATION C7000
J 0
(-1400 5550);
DISPLAY 0.638298 (-1400 5550);
FORCEPROP 0 LAST $SEC 1
J 0
(-1400 5600);
DISPLAY 0.680851 (-1400 5600);
PAINT MONO (-1400 5600);
DISPLAY INVISIBLE (-1400 5600);
FORCEPROP 0 LAST CDS_SEC 1
J 0
(-1400 5600);
DISPLAY 0.680851 (-1400 5600);
DISPLAY INVISIBLE (-1400 5600);
FORCEPROP 1 LASTPIN (-1450 5550) $PN 1
J 0
(-1440 5535);
DISPLAY 0.787234 (-1440 5535);
PAINT MONO (-1440 5535);
FORCEPROP 1 LASTPIN (-1450 5350) $PN 2
J 0
(-1440 5335);
DISPLAY 0.787234 (-1440 5335);
PAINT MONO (-1440 5335);
FORCEPROP 1 LAST VALUE 470UF
J 0
(-1400 5500);
DISPLAY 0.510638 (-1400 5500);
FORCEPROP 1 LAST PACK_TYPE SMLF
J 0
(-1400 5300);
DISPLAY 0.510638 (-1400 5300);
FORCEPROP 1 LAST VOLTAGE 2.5V
J 0
(-1400 5400);
DISPLAY 0.510638 (-1400 5400);
FORCEPROP 1 LAST MATERIAL SPCAP
J 0
(-1400 5350);
DISPLAY 0.510638 (-1400 5350);
FORCEPROP 1 LAST TOLERANCE 20%
J 0
(-1400 5450);
DISPLAY 0.510638 (-1400 5450);
FORCEPROP 2 LAST CDS_LIB pure_quanta
J 0
(-1450 5450);
DISPLAY INVISIBLE (-1450 5450);
FORCEPROP 1 LAST PATH I98
J 0
(-1400 5600);
DISPLAY 0.978723 (-1400 5600);
DISPLAY INVISIBLE (-1400 5600);
FORCEPROP 1 LAST PART_NUMBER CH747LM8818
J 0
(-1400 5250);
DISPLAY 0.404255 (-1400 5250);
DISPLAY INVISIBLE (-1400 5250);
FORCEADD Q_CAPP..1
(-1050 2250);
FORCEPROP 1 LAST LOCATION C7008
J 0
(-1000 2350);
DISPLAY 0.787234 (-1000 2350);
FORCEPROP 0 LAST $SEC 1
J 0
(-1000 2400);
DISPLAY 0.680851 (-1000 2400);
PAINT MONO (-1000 2400);
DISPLAY INVISIBLE (-1000 2400);
FORCEPROP 0 LAST CDS_SEC 1
J 0
(-1000 2400);
DISPLAY 0.680851 (-1000 2400);
DISPLAY INVISIBLE (-1000 2400);
FORCEPROP 1 LASTPIN (-1050 2350) $PN 1
J 0
(-1040 2335);
DISPLAY 0.787234 (-1040 2335);
PAINT MONO (-1040 2335);
FORCEPROP 1 LASTPIN (-1050 2150) $PN 2
J 0
(-1040 2135);
DISPLAY 0.787234 (-1040 2135);
PAINT MONO (-1040 2135);
FORCEPROP 1 LAST VALUE 470UF
J 0
(-1000 2300);
DISPLAY 0.510638 (-1000 2300);
FORCEPROP 1 LAST TOLERANCE 20%
J 0
(-1000 2250);
DISPLAY 0.510638 (-1000 2250);
FORCEPROP 1 LAST PACK_TYPE SMLF
J 0
(-1000 2100);
DISPLAY 0.510638 (-1000 2100);
FORCEPROP 1 LAST VOLTAGE 2.5V
J 0
(-1000 2200);
DISPLAY 0.510638 (-1000 2200);
FORCEPROP 1 LAST MATERIAL SPCAP
J 0
(-1000 2150);
DISPLAY 0.510638 (-1000 2150);
FORCEPROP 2 LAST CDS_LIB pure_quanta
J 0
(-1050 2250);
DISPLAY INVISIBLE (-1050 2250);
FORCEPROP 1 LAST PATH I99
J 0
(-1000 2400);
DISPLAY 0.978723 (-1000 2400);
DISPLAY INVISIBLE (-1000 2400);
FORCEPROP 1 LAST PART_NUMBER CH747LM8818
J 0
(-1000 2050);
DISPLAY 0.404255 (-1000 2050);
DISPLAY INVISIBLE (-1000 2050);
FORCEADD CAD_NOTE..1
(-8150 2950);
FORCEPROP 0 LAST S1 L26/R960 COLAY WITH R951/R952
J 0
(-8275 2825);
DISPLAY 0.808511 (-8275 2825);
PAINT WHITE (-8275 2825);
FORCEPROP 2 LAST CDS_LIB pure_quanta_power
J 0
(-8150 2950);
DISPLAY INVISIBLE (-8150 2950);
FORCEPROP 1 LAST COMMENT_BODY TRUE
J 0
(-8125 3050);
DISPLAY 0.978723 (-8125 3050);
DISPLAY INVISIBLE (-8125 3050);
FORCEADD DNS..2
(-7675 3550);
PAINT RED (-7675 3550);
FORCEPROP 2 LAST CDS_LIB mstr_misc
J 0
(-7675 3550);
DISPLAY INVISIBLE (-7675 3550);
FORCEPROP 1 LAST COMMENT_BODY TRUE
J 0
(-7675 3550);
DISPLAY INVISIBLE (-7675 3550);
FORCEADD CAD_NOTE..1
(-5100 2450);
FORCEPROP 0 LAST S1 R961 AND R962 COLAY
J 0
(-5225 2325);
DISPLAY 0.808511 (-5225 2325);
PAINT WHITE (-5225 2325);
FORCEPROP 2 LAST CDS_LIB pure_quanta_power
J 0
(-5100 2450);
DISPLAY INVISIBLE (-5100 2450);
FORCEPROP 1 LAST COMMENT_BODY TRUE
J 0
(-5075 2550);
DISPLAY 0.978723 (-5075 2550);
DISPLAY INVISIBLE (-5075 2550);
FORCEADD DNS..2
(-4350 2750);
PAINT RED (-4350 2750);
FORCEPROP 2 LAST CDS_LIB mstr_misc
J 0
(-4350 2750);
DISPLAY INVISIBLE (-4350 2750);
FORCEPROP 1 LAST COMMENT_BODY TRUE
J 0
(-4350 2750);
DISPLAY INVISIBLE (-4350 2750);
FORCEADD QUANTA_TITLE_BLOCK_C..1
(0 0);
FORCEPROP 0 LAST CDS_CON_LAST_MODIFIED Thu Sep 14 16:13:08 2023
J 0
(-1885 15);
DISPLAY INVISIBLE (-1885 15);
FORCEPROP 1 LAST CUSTOM_TXT_CDS <CON_LAST_MODIFIED>
J 0
(-1885 15);
DISPLAY 0.978723 (-1885 15);
FORCEPROP 2 LAST CUSTOM_TXT_CDS <XR_PAGE_TITLE>
J 0
(-7890 5250);
DISPLAY 0.638298 (-7890 5250);
PAINT PINK (-7890 5250);
DISPLAY INVISIBLE (-7890 5250);
FORCEPROP 1 LAST CUSTOM_TXT_CDS <NAME_2>
J 0
(-3175 50);
FORCEPROP 1 LAST CUSTOM_TXT_CDS <NAME_1>
J 0
(-3175 175);
FORCEPROP 1 LAST CUSTOM_TXT_CDS <Q_NUMBER>
J 0
(-1403 103);
DISPLAY 1.212766 (-1403 103);
FORCEPROP 1 LAST CUSTOM_TXT_CDS <Q_PROJ>
J 0
(-2382 102);
DISPLAY 1.212766 (-2382 102);
FORCEPROP 1 LAST CUSTOM_TXT_CDS <Q_REV>
J 0
(-184 103);
DISPLAY 1.212766 (-184 103);
FORCEPROP 1 LAST CUSTOM_TXT_CDS <CON_PAGE_NUM> OF <CON_TOTAL_PAGES>
J 0
(-446 18);
DISPLAY 0.978723 (-446 18);
FORCEPROP 1 LAST Q_TITLE RETIMER_CPU0_P0 DECAPS(8)
J 0
(-9366 26);
DISPLAY 2.446809 (-9366 26);
PAINT GREEN (-9366 26);
FORCEPROP 2 LAST CDS_LIB pure_quanta
J 0
(0 0);
DISPLAY INVISIBLE (0 0);
FORCEPROP 1 LAST CDS_LMAN_SYM_OUTLINE -9475,6775,100,-125
J 0
(0 0);
DISPLAY 0.468085 (0 0);
PAINT GREEN (0 0);
DISPLAY INVISIBLE (0 0);
FORCEPROP 2 LAST PAGE_BORDER TRUE
J 0
(-7890 5250);
DISPLAY 0.638298 (-7890 5250);
PAINT PINK (-7890 5250);
DISPLAY INVISIBLE (-7890 5250);
FORCEPROP 2 LAST CDS_XR_PAGE_TITLE CR-280 : @T6G_MB_LIB.T6G(SCH_1):PAGE280
J 0
(-7890 5250);
DISPLAY 0.638298 (-7890 5250);
PAINT PINK (-7890 5250);
DISPLAY INVISIBLE (-7890 5250);
FORCEPROP 1 LAST Q_DEPT BU9
J 1
(-3763 49);
DISPLAY 1.957447 (-3763 49);
PAINT GREEN (-3763 49);
DISPLAY INVISIBLE (-3763 49);
FORCEPROP 1 LAST COMMENT_BODY TRUE
J 0
(12 -13);
DISPLAY 0.978723 (12 -13);
PAINT GREEN (12 -13);
DISPLAY INVISIBLE (12 -13);
FORCEADD DNS..2
(-7675 3725);
PAINT RED (-7675 3725);
FORCEPROP 2 LAST CDS_LIB mstr_misc
J 0
(-7675 3725);
DISPLAY INVISIBLE (-7675 3725);
FORCEPROP 1 LAST COMMENT_BODY TRUE
J 0
(-7675 3725);
DISPLAY INVISIBLE (-7675 3725);
FORCEADD DNS..2
(-8025 4100);
PAINT RED (-8025 4100);
FORCEPROP 2 LAST CDS_LIB mstr_misc
J 0
(-8025 4100);
DISPLAY INVISIBLE (-8025 4100);
FORCEPROP 1 LAST COMMENT_BODY TRUE
J 0
(-8025 4100);
DISPLAY INVISIBLE (-8025 4100);
WIRE 16 -1 (-450 5700)(-450 5525);
WIRE 16 -1 (-850 5700)(-450 5700);
WIRE 16 -1 (-850 5550)(-850 5700);
WIRE 16 -1 (-1150 5700)(-850 5700);
WIRE 16 -1 (-1450 5700)(-1150 5700);
WIRE 16 -1 (-1150 5550)(-1150 5700);
WIRE 16 -1 (-1450 5550)(-1450 5700);
WIRE 16 -1 (-1725 5700)(-1450 5700);
WIRE 16 -1 (-1725 5700)(-1725 5550);
WIRE 16 -1 (-2050 5700)(-1725 5700);
WIRE 16 -1 (-2325 5700)(-2050 5700);
WIRE 16 -1 (-2050 5700)(-2050 5550);
WIRE 16 -1 (-2325 5550)(-2325 5700);
WIRE 16 -1 (-2675 5700)(-2325 5700);
WIRE 16 -1 (-2950 5700)(-2675 5700);
WIRE 16 -1 (-2675 5700)(-2675 5550);
WIRE 16 -1 (-2950 5700)(-2950 5550);
WIRE 16 -1 (-3250 5700)(-2950 5700);
WIRE 16 -1 (-3525 5700)(-3250 5700);
WIRE 16 -1 (-3250 5700)(-3250 5550);
WIRE 16 -1 (-3525 5700)(-3525 5550);
WIRE 16 -1 (-3525 5700)(-3825 5700);
WIRE 16 -1 (-3825 5700)(-3825 5575);
WIRE 16 -1 (-3825 5700)(-4100 5700);
WIRE 16 -1 (-4200 5700)(-4100 5700);
WIRE 16 -1 (-4100 5700)(-4100 5575);
WIRE 16 -1 (-4300 5700)(-4200 5700);
WIRE 16 -1 (-4200 5700)(-4200 5050);
WIRE 16 -1 (-4200 5050)(-2000 5050);
WIRE 16 -1 (-4300 5925)(-4300 5700);
WIRE 16 -1 (-4300 4450)(-4300 5700);
WIRE 16 -1 (-3925 4450)(-4300 4450);
WIRE 16 -1 (-4300 4450)(-4300 2875);
WIRE 16 -1 (-2000 5050)(-1650 5050);
WIRE 16 -1 (-2000 5050)(-2000 4975);
WIRE 16 -1 (-1650 5050)(-1375 5050);
WIRE 16 -1 (-1650 5050)(-1650 4975);
WIRE 16 -1 (-1375 5050)(-1125 5050);
WIRE 16 -1 (-1375 5050)(-1375 4975);
WIRE 16 -1 (-1125 5050)(-850 5050);
WIRE 16 -1 (-1125 5050)(-1125 4975);
WIRE 16 -1 (-850 5050)(-850 4975);
WIRE 16 -1 (-2000 4775)(-2000 4600);
WIRE 16 -1 (-2000 4600)(-1650 4600);
WIRE 16 -1 (-1650 4600)(-1375 4600);
WIRE 16 -1 (-1650 4775)(-1650 4600);
WIRE 16 -1 (-1375 4775)(-1375 4600);
WIRE 16 -1 (-1375 4600)(-1125 4600);
WIRE 16 -1 (-1125 4600)(-850 4600);
WIRE 16 -1 (-1125 4775)(-1125 4600);
WIRE 16 -1 (-850 4600)(-450 4600);
WIRE 16 -1 (-850 4775)(-850 4600);
WIRE 16 -1 (-450 5150)(-450 4600);
WIRE 16 -1 (-450 4600)(-450 4550);
WIRE 16 -1 (-450 5325)(-450 5150);
WIRE 16 -1 (-450 5150)(-850 5150);
WIRE 16 -1 (-850 5350)(-850 5150);
WIRE 16 -1 (-850 5150)(-1150 5150);
WIRE 16 -1 (-1150 5350)(-1150 5150);
WIRE 16 -1 (-1450 5150)(-1150 5150);
WIRE 16 -1 (-1450 5350)(-1450 5150);
WIRE 16 -1 (-1450 5150)(-1725 5150);
WIRE 16 -1 (-1725 5350)(-1725 5150);
WIRE 16 -1 (-2050 5150)(-1725 5150);
WIRE 16 -1 (-2050 5350)(-2050 5150);
WIRE 16 -1 (-2325 5150)(-2050 5150);
WIRE 16 -1 (-2325 5350)(-2325 5150);
WIRE 16 -1 (-2675 5150)(-2325 5150);
WIRE 16 -1 (-2675 5350)(-2675 5150);
WIRE 16 -1 (-2950 5150)(-2675 5150);
WIRE 16 -1 (-2950 5350)(-2950 5150);
WIRE 16 -1 (-3250 5150)(-2950 5150);
WIRE 16 -1 (-3250 5350)(-3250 5150);
WIRE 16 -1 (-3525 5150)(-3250 5150);
WIRE 16 -1 (-3525 5350)(-3525 5150);
WIRE 16 -1 (-3525 5150)(-3825 5150);
WIRE 16 -1 (-3825 5375)(-3825 5150);
WIRE 16 -1 (-4100 5150)(-3825 5150);
WIRE 16 -1 (-4100 5375)(-4100 5150);
WIRE 16 -1 (-475 2500)(-475 2350);
WIRE 16 -1 (-750 2500)(-475 2500);
WIRE 16 -1 (-750 2500)(-750 2350);
WIRE 16 -1 (-1050 2500)(-750 2500);
WIRE 16 -1 (-1050 2500)(-1050 2350);
WIRE 16 -1 (-1375 2500)(-1050 2500);
WIRE 16 -1 (-1375 2350)(-1375 2500);
WIRE 16 -1 (-1375 2500)(-1625 2500);
WIRE 16 -1 (-1625 2350)(-1625 2500);
WIRE 16 -1 (-1900 2500)(-1625 2500);
WIRE 16 -1 (-1900 2350)(-1900 2500);
WIRE 16 -1 (-2175 2500)(-1900 2500);
WIRE 16 -1 (-2175 2350)(-2175 2500);
WIRE 16 -1 (-2425 2500)(-2175 2500);
WIRE 16 -1 (-2425 2350)(-2425 2500);
WIRE 16 -1 (-2675 2500)(-2425 2500);
WIRE 16 -1 (-2675 2500)(-2675 2350);
WIRE 16 -1 (-2900 2500)(-2675 2500);
WIRE 16 -1 (-2900 2500)(-2900 2350);
WIRE 16 -1 (-3200 2500)(-2900 2500);
WIRE 16 -1 (-3200 2500)(-3200 2350);
WIRE 16 -1 (-3650 2500)(-3200 2500);
WIRE 16 -1 (-3650 3175)(-3650 2500);
WIRE 16 -1 (-3650 2500)(-3825 2500);
WIRE 16 -1 (-3650 3175)(-3475 3175);
WIRE 16 -1 (-3650 3800)(-3650 3175);
WIRE 16 -1 (-3650 4450)(-3650 3800);
WIRE 16 -1 (-3650 3800)(-3475 3800);
WIRE 16 -1 (-3475 3175)(-3250 3175);
WIRE 16 -1 (-3475 3175)(-3475 3050);
WIRE 16 -1 (-3250 3175)(-3000 3175);
WIRE 16 -1 (-3250 3175)(-3250 3050);
WIRE 16 -1 (-3475 3800)(-3250 3800);
WIRE 16 -1 (-3475 3675)(-3475 3800);
WIRE 16 -1 (-3650 4450)(-3475 4450);
WIRE 16 -1 (-3725 4450)(-3650 4450);
WIRE 16 -1 (-3475 4450)(-3350 4450);
WIRE 16 -1 (-3475 4450)(-3475 4300);
WIRE 16 -1 (-3250 3800)(-3025 3800);
WIRE 16 -1 (-3250 3675)(-3250 3800);
WIRE 16 -1 (-2725 3175)(-3000 3175);
WIRE 16 -1 (-3000 3175)(-3000 3050);
WIRE 16 -1 (-2450 3175)(-2725 3175);
WIRE 16 -1 (-2725 3175)(-2725 3050);
WIRE 16 -1 (-3025 3800)(-2800 3800);
WIRE 16 -1 (-3025 3675)(-3025 3800);
WIRE 16 -1 (-3350 4675)(-3350 4450);
WIRE 16 -1 (-3350 4450)(-3250 4450);
WIRE 16 -1 (-3025 4450)(-3250 4450);
WIRE 16 -1 (-3250 4450)(-3250 4300);
WIRE 16 -1 (-2800 3800)(-2550 3800);
WIRE 16 -1 (-2800 3675)(-2800 3800);
WIRE 16 -1 (-2200 3175)(-2450 3175);
WIRE 16 -1 (-2450 3175)(-2450 3050);
WIRE 16 -1 (-1925 3175)(-2200 3175);
WIRE 16 -1 (-2200 3025)(-2200 3175);
WIRE 16 -1 (-2550 3800)(-2325 3800);
WIRE 16 -1 (-2550 3675)(-2550 3800);
WIRE 16 -1 (-2800 4450)(-3025 4450);
WIRE 16 -1 (-3025 4450)(-3025 4300);
WIRE 16 -1 (-2550 4450)(-2800 4450);
WIRE 16 -1 (-2800 4450)(-2800 4300);
WIRE 16 -1 (-2325 3800)(-2100 3800);
WIRE 16 -1 (-2325 3675)(-2325 3800);
WIRE 16 -1 (-1675 3175)(-1925 3175);
WIRE 16 -1 (-1925 3025)(-1925 3175);
WIRE 16 -1 (-1675 3175)(-1375 3175);
WIRE 16 -1 (-1675 3175)(-1675 3025);
WIRE 16 -1 (-2100 3800)(-1875 3800);
WIRE 16 -1 (-2100 3675)(-2100 3800);
WIRE 16 -1 (-2325 4450)(-2550 4450);
WIRE 16 -1 (-2550 4450)(-2550 4300);
WIRE 16 -1 (-2100 4450)(-2325 4450);
WIRE 16 -1 (-2325 4450)(-2325 4300);
WIRE 16 -1 (-1875 3800)(-1650 3800);
WIRE 16 -1 (-1875 3675)(-1875 3800);
WIRE 16 -1 (-1375 3175)(-1375 3025);
WIRE 16 -1 (-1400 3800)(-1650 3800);
WIRE 16 -1 (-1650 3675)(-1650 3800);
WIRE 16 -1 (-1875 4450)(-2100 4450);
WIRE 16 -1 (-2100 4450)(-2100 4300);
WIRE 16 -1 (-1575 4450)(-1875 4450);
WIRE 16 -1 (-1875 4450)(-1875 4300);
WIRE 16 -1 (-1400 3800)(-1400 3675);
WIRE 16 -1 (-1575 4450)(-1275 4450);
WIRE 16 -1 (-1575 4450)(-1575 4300);
WIRE 16 -1 (-1275 4450)(-1275 4300);
WIRE 16 -1 (-3475 3475)(-3475 3350);
WIRE 16 -1 (-3475 3350)(-3250 3350);
WIRE 16 -1 (-3250 3350)(-3025 3350);
WIRE 16 -1 (-3250 3475)(-3250 3350);
WIRE 16 -1 (-3025 3350)(-2800 3350);
WIRE 16 -1 (-3025 3475)(-3025 3350);
WIRE 16 -1 (-2800 3350)(-2550 3350);
WIRE 16 -1 (-2800 3475)(-2800 3350);
WIRE 16 -1 (-2550 3350)(-2325 3350);
WIRE 16 -1 (-2550 3475)(-2550 3350);
WIRE 16 -1 (-2325 3350)(-2100 3350);
WIRE 16 -1 (-2325 3475)(-2325 3350);
WIRE 16 -1 (-2100 3350)(-1875 3350);
WIRE 16 -1 (-2100 3475)(-2100 3350);
WIRE 16 -1 (-1875 3350)(-1650 3350);
WIRE 16 -1 (-1875 3475)(-1875 3350);
WIRE 16 -1 (-1400 3350)(-1650 3350);
WIRE 16 -1 (-1650 3475)(-1650 3350);
WIRE 16 -1 (-875 3350)(-1400 3350);
WIRE 16 -1 (-1400 3475)(-1400 3350);
WIRE 16 -1 (-875 3950)(-875 3350);
WIRE 16 -1 (-875 3350)(-875 2625);
WIRE 16 -1 (-875 2625)(-1375 2625);
WIRE 16 -1 (-875 2625)(-875 2600);
WIRE 16 -1 (-875 3950)(-1275 3950);
WIRE 16 -1 (-1275 4100)(-1275 3950);
WIRE 16 -1 (-1275 3950)(-1575 3950);
WIRE 16 -1 (-1675 2625)(-1375 2625);
WIRE 16 -1 (-1375 2825)(-1375 2625);
WIRE 16 -1 (-1675 2825)(-1675 2625);
WIRE 16 -1 (-1675 2625)(-1925 2625);
WIRE 16 -1 (-1575 4100)(-1575 3950);
WIRE 16 -1 (-1575 3950)(-1875 3950);
WIRE 16 -1 (-1875 4100)(-1875 3950);
WIRE 16 -1 (-1875 3950)(-2100 3950);
WIRE 16 -1 (-1925 2825)(-1925 2625);
WIRE 16 -1 (-1925 2625)(-2200 2625);
WIRE 16 -1 (-2200 2825)(-2200 2625);
WIRE 16 -1 (-2200 2625)(-2450 2625);
WIRE 16 -1 (-2100 4100)(-2100 3950);
WIRE 16 -1 (-2100 3950)(-2325 3950);
WIRE 16 -1 (-2325 4100)(-2325 3950);
WIRE 16 -1 (-2325 3950)(-2550 3950);
WIRE 16 -1 (-2450 2850)(-2450 2625);
WIRE 16 -1 (-2450 2625)(-2725 2625);
WIRE 16 -1 (-2725 2850)(-2725 2625);
WIRE 16 -1 (-2725 2625)(-3000 2625);
WIRE 16 -1 (-2550 4100)(-2550 3950);
WIRE 16 -1 (-2550 3950)(-2800 3950);
WIRE 16 -1 (-2800 4100)(-2800 3950);
WIRE 16 -1 (-3025 3950)(-2800 3950);
WIRE 16 -1 (-3000 2850)(-3000 2625);
WIRE 16 -1 (-3250 2625)(-3000 2625);
WIRE 16 -1 (-3250 2850)(-3250 2625);
WIRE 16 -1 (-3475 2625)(-3250 2625);
WIRE 16 -1 (-3025 4100)(-3025 3950);
WIRE 16 -1 (-3250 3950)(-3025 3950);
WIRE 16 -1 (-3250 4100)(-3250 3950);
WIRE 16 -1 (-3475 3950)(-3250 3950);
WIRE 16 -1 (-3475 2850)(-3475 2625);
WIRE 16 -1 (-3475 4100)(-3475 3950);
WIRE 16 -1 (-8150 4450)(-8150 4300);
WIRE 16 -1 (-8150 5175)(-8150 4450);
WIRE 16 -1 (-8150 4450)(-7875 4450);
WIRE 16 -1 (-8150 4300)(-8100 4300);
WIRE 16 -1 (-8150 4300)(-8200 4300);
WIRE 16 -1 (-8200 4300)(-8200 4225);
WIRE 16 -1 (-8100 4300)(-8100 4200);
WIRE 16 -1 (-7050 5175)(-8150 5175);
WIRE 16 -1 (-8150 5250)(-8150 5175);
WIRE 16 -1 (-7050 5175)(-6800 5175);
WIRE 16 -1 (-7050 5175)(-7050 5125);
WIRE 16 -1 (-6800 5175)(-6550 5175);
WIRE 16 -1 (-6800 5175)(-6800 5125);
WIRE 16 -1 (-6550 5175)(-6300 5175);
WIRE 16 -1 (-6550 5175)(-6550 5100);
WIRE 16 -1 (-6300 5175)(-6300 5100);
WIRE 16 -1 (-6300 4900)(-6300 4775);
WIRE 16 -1 (-6375 4775)(-6300 4775);
WIRE 16 -1 (-6550 4775)(-6375 4775);
WIRE 16 -1 (-6550 4900)(-6550 4775);
WIRE 16 -1 (-6800 4775)(-6550 4775);
WIRE 16 -1 (-6800 4925)(-6800 4775);
WIRE 16 -1 (-7050 4775)(-6800 4775);
WIRE 16 -1 (-7050 4925)(-7050 4775);
WIRE 16 -1 (-5150 4450)(-5150 4300);
WIRE 16 -1 (-5150 4450)(-5425 4450);
WIRE 16 -1 (-5425 4450)(-5425 4300);
WIRE 16 -1 (-5425 4450)(-5675 4450);
WIRE 16 -1 (-5675 4450)(-5675 4300);
WIRE 16 -1 (-5675 4450)(-5925 4450);
WIRE 16 -1 (-5925 4450)(-5925 4300);
WIRE 16 -1 (-6150 4450)(-5925 4450);
WIRE 16 -1 (-6150 4450)(-6350 4450);
WIRE 16 -1 (-6150 4450)(-6150 4300);
WIRE 16 -1 (-6350 4450)(-6350 4300);
WIRE 16 -1 (-6350 4450)(-6575 4450);
WIRE 16 -1 (-6575 4450)(-6575 4300);
WIRE 16 -1 (-6775 4450)(-6575 4450);
WIRE 16 -1 (-6775 4450)(-6775 4300);
WIRE 16 -1 (-6775 4450)(-6975 4450);
WIRE 16 -1 (-6975 4450)(-6975 4300);
WIRE 16 -1 (-7200 4450)(-6975 4450);
WIRE 16 -1 (-7200 4450)(-7300 4450);
WIRE 16 -1 (-7200 4450)(-7200 4300);
WIRE 16 -1 (-7300 4625)(-7300 4450);
WIRE 16 -1 (-7300 4450)(-7675 4450);
WIRE 16 -1 (-7300 3675)(-7300 4450);
WIRE 16 -1 (-7400 3675)(-7300 3675);
WIRE 16 -1 (-7400 3775)(-7400 3675);
WIRE 16 -1 (-7400 3675)(-7400 3575);
WIRE 16 -1 (-7600 3575)(-7400 3575);
WIRE 16 -1 (-7600 3775)(-7400 3775);
WIRE 16 -1 (-5150 4100)(-5150 4000);
WIRE 16 -1 (-5425 4000)(-5150 4000);
WIRE 16 -1 (-5425 4100)(-5425 4000);
WIRE 16 -1 (-5675 4000)(-5425 4000);
WIRE 16 -1 (-5675 4100)(-5675 4000);
WIRE 16 -1 (-5925 4000)(-5675 4000);
WIRE 16 -1 (-5925 4100)(-5925 4000);
WIRE 16 -1 (-6150 4000)(-5925 4000);
WIRE 16 -1 (-6350 4000)(-6150 4000);
WIRE 16 -1 (-6150 4100)(-6150 4000);
WIRE 16 -1 (-6150 4000)(-6150 3925);
WIRE 16 -1 (-6350 4100)(-6350 4000);
WIRE 16 -1 (-6575 4000)(-6350 4000);
WIRE 16 -1 (-6575 4100)(-6575 4000);
WIRE 16 -1 (-6775 4000)(-6575 4000);
WIRE 16 -1 (-6775 4100)(-6775 4000);
WIRE 16 -1 (-6975 4000)(-6775 4000);
WIRE 16 -1 (-6975 4100)(-6975 4000);
WIRE 16 -1 (-7200 4000)(-6975 4000);
WIRE 16 -1 (-7200 4100)(-7200 4000);
WIRE 16 -1 (-6775 3025)(-6775 2850);
WIRE 16 -1 (-6775 2850)(-6500 2850);
WIRE 16 -1 (-6500 3000)(-6500 2850);
WIRE 16 -1 (-6500 2850)(-6500 2750);
WIRE 16 -1 (-475 2025)(-475 2150);
WIRE 16 -1 (-475 2025)(-750 2025);
WIRE 16 -1 (-750 2150)(-750 2025);
WIRE 16 -1 (-1050 2025)(-750 2025);
WIRE 16 -1 (-1050 2150)(-1050 2025);
WIRE 16 -1 (-1375 2025)(-1050 2025);
WIRE 16 -1 (-1625 2025)(-1375 2025);
WIRE 16 -1 (-1375 2150)(-1375 2025);
WIRE 16 -1 (-1375 2025)(-1375 1875);
WIRE 16 -1 (-1625 2150)(-1625 2025);
WIRE 16 -1 (-1625 2025)(-1900 2025);
WIRE 16 -1 (-1900 2150)(-1900 2025);
WIRE 16 -1 (-2175 2025)(-1900 2025);
WIRE 16 -1 (-2175 2150)(-2175 2025);
WIRE 16 -1 (-2425 2025)(-2175 2025);
WIRE 16 -1 (-2425 2150)(-2425 2025);
WIRE 16 -1 (-2675 2025)(-2425 2025);
WIRE 16 -1 (-2675 2150)(-2675 2025);
WIRE 16 -1 (-2900 2025)(-2675 2025);
WIRE 16 -1 (-2900 2150)(-2900 2025);
WIRE 16 -1 (-3200 2025)(-2900 2025);
WIRE 16 -1 (-3200 2150)(-3200 2025);
WIRE 16 -1 (-6500 3350)(-6500 3200);
WIRE 16 -1 (-6775 3350)(-6500 3350);
WIRE 16 -1 (-6775 3350)(-6900 3350);
WIRE 16 -1 (-6775 3225)(-6775 3350);
WIRE 16 -1 (-8150 3350)(-6900 3350);
WIRE 16 -1 (-6900 3350)(-6900 3450);
WIRE 16 -1 (-8150 3350)(-8150 3675);
WIRE 16 -1 (-8150 3675)(-8150 3850);
WIRE 16 -1 (-8150 3675)(-8050 3675);
WIRE 16 -1 (-8050 3775)(-8050 3675);
WIRE 16 -1 (-8050 3675)(-8050 3575);
WIRE 16 -1 (-8150 3850)(-8100 3850);
WIRE 16 -1 (-8200 3850)(-8150 3850);
WIRE 16 -1 (-8200 3850)(-8200 4025);
WIRE 16 -1 (-8100 3850)(-8100 4000);
WIRE 16 -1 (-8050 3575)(-7800 3575);
WIRE 16 -1 (-7800 3775)(-8050 3775);
WIRE 16 -1 (-3025 1050)(-3025 925);
WIRE 16 -1 (-3025 925)(-2775 925);
WIRE 16 -1 (-2775 1050)(-2775 925);
WIRE 16 -1 (-2775 925)(-2475 925);
WIRE 16 -1 (-2475 1050)(-2475 925);
WIRE 16 -1 (-2475 925)(-2325 925);
WIRE 16 -1 (-2225 925)(-2325 925);
WIRE 16 -1 (-2325 925)(-2325 875);
WIRE 16 -1 (-2225 1050)(-2225 925);
WIRE 16 -1 (-4300 2675)(-4300 2500);
WIRE 16 -1 (-4300 2500)(-4025 2500);
WIRE 16 -1 (-4300 1400)(-4300 2500);
WIRE 16 -1 (-4300 1400)(-3150 1400);
WIRE 16 -1 (-3025 1400)(-3150 1400);
WIRE 16 -1 (-3150 1625)(-3150 1400);
WIRE 16 -1 (-2775 1400)(-3025 1400);
WIRE 16 -1 (-3025 1400)(-3025 1250);
WIRE 16 -1 (-2475 1400)(-2775 1400);
WIRE 16 -1 (-2775 1400)(-2775 1250);
WIRE 16 -1 (-2225 1400)(-2475 1400);
WIRE 16 -1 (-2475 1250)(-2475 1400);
WIRE 16 -1 (-2225 1250)(-2225 1400);
DOT 1 (-1650 5050);
DOT 1 (-1375 4600);
DOT 1 (-1375 5050);
DOT 1 (-1125 4600);
DOT 1 (-1125 5050);
DOT 1 (-850 4600);
DOT 1 (-850 5150);
DOT 1 (-450 4600);
DOT 1 (-3025 3800);
DOT 1 (-3025 3950);
DOT 1 (-450 5150);
DOT 1 (-1150 5150);
DOT 1 (-2550 4450);
DOT 1 (-1725 5700);
DOT 1 (-2675 5150);
DOT 1 (-4200 5700);
DOT 1 (-2950 5150);
DOT 1 (-3250 5150);
DOT 1 (-3350 4450);
DOT 1 (-3525 5150);
DOT 1 (-3250 3350);
DOT 1 (-1450 5700);
DOT 1 (-1725 5150);
DOT 1 (-1450 5150);
DOT 1 (-1150 5700);
DOT 1 (-850 5700);
DOT 1 (-750 2025);
DOT 1 (-750 2500);
DOT 1 (-1050 2025);
DOT 1 (-1050 2500);
DOT 1 (-1675 3175);
DOT 1 (-1925 2625);
DOT 1 (-1925 3175);
DOT 1 (-2200 2625);
DOT 1 (-2450 2625);
DOT 1 (-2450 3175);
DOT 1 (-2725 2625);
DOT 1 (-2725 3175);
DOT 1 (-2425 2500);
DOT 1 (-2900 2025);
DOT 1 (-2775 925);
DOT 1 (-2775 1400);
DOT 1 (-2475 925);
DOT 1 (-2475 1400);
DOT 1 (-2425 2025);
DOT 1 (-2175 2500);
DOT 1 (-2800 3800);
DOT 1 (-2800 3350);
DOT 1 (-2675 2500);
DOT 1 (-2675 2025);
DOT 1 (-2175 2025);
DOT 1 (-1625 2025);
DOT 1 (-3200 2500);
DOT 1 (-3150 1400);
DOT 1 (-3025 1400);
DOT 1 (-1900 2025);
DOT 1 (-2325 3950);
DOT 1 (-1900 2500);
DOT 1 (-3000 2625);
DOT 1 (-1650 3350);
DOT 1 (-2325 3350);
DOT 1 (-1875 3350);
DOT 1 (-3000 3175);
DOT 1 (-2550 3350);
DOT 1 (-2100 4450);
DOT 1 (-6575 4000);
DOT 1 (-2100 3950);
DOT 1 (-1575 4450);
DOT 1 (-1875 3800);
DOT 1 (-3650 3800);
DOT 1 (-3250 3800);
DOT 1 (-3650 4450);
DOT 1 (-2800 4450);
DOT 1 (-2100 3800);
DOT 1 (-2550 3800);
DOT 1 (-3475 3800);
DOT 1 (-3250 2625);
DOT 1 (-2550 3950);
DOT 1 (-1650 3800);
DOT 1 (-2100 3350);
DOT 1 (-1400 3350);
DOT 1 (-3025 3350);
DOT 1 (-5425 4450);
DOT 1 (-3025 4450);
DOT 1 (-2325 3800);
DOT 1 (-1575 3950);
DOT 1 (-2325 4450);
DOT 1 (-2800 3950);
DOT 1 (-3250 3950);
DOT 1 (-1875 4450);
DOT 1 (-6775 4450);
DOT 1 (-1875 3950);
DOT 1 (-6150 4000);
DOT 1 (-6150 4450);
DOT 1 (-7050 5175);
DOT 1 (-6800 4775);
DOT 1 (-7200 4450);
DOT 1 (-6550 5175);
DOT 1 (-6800 5175);
DOT 1 (-5925 4000);
DOT 1 (-6775 3350);
DOT 1 (-6900 3350);
DOT 1 (-7300 4450);
DOT 1 (-2900 2500);
DOT 1 (-6575 4450);
DOT 1 (-8150 3675);
DOT 1 (-8150 5175);
DOT 1 (-7400 3675);
DOT 1 (-6975 4000);
DOT 1 (-5675 4450);
DOT 1 (-4300 4450);
DOT 1 (-4300 5700);
DOT 1 (-2325 925);
DOT 1 (-3650 3175);
DOT 1 (-875 2625);
DOT 1 (-3475 4450);
DOT 1 (-1275 3950);
DOT 1 (-4300 2500);
DOT 1 (-3650 2500);
DOT 1 (-6975 4450);
DOT 1 (-8150 4450);
DOT 1 (-8150 3850);
DOT 1 (-8050 3675);
DOT 1 (-8150 4300);
DOT 1 (-6500 2850);
DOT 1 (-3250 3175);
DOT 1 (-3475 3175);
DOT 1 (-5425 4000);
DOT 1 (-5675 4000);
DOT 1 (-5925 4450);
DOT 1 (-6350 4450);
DOT 1 (-6775 4000);
DOT 1 (-6550 4775);
DOT 1 (-6350 4000);
DOT 1 (-4100 5700);
DOT 1 (-2325 5700);
DOT 1 (-2675 5700);
DOT 1 (-2950 5700);
DOT 1 (-3250 5700);
DOT 1 (-3525 5700);
DOT 1 (-3825 5700);
DOT 1 (-3825 5150);
DOT 1 (-2050 5700);
DOT 1 (-1675 2625);
DOT 1 (-1625 2500);
DOT 1 (-2200 3175);
DOT 1 (-3250 4450);
DOT 1 (-875 3350);
DOT 1 (-1375 2025);
DOT 1 (-1375 2625);
DOT 1 (-1375 2500);
DOT 1 (-2325 5150);
DOT 1 (-2050 5150);
DOT 1 (-2000 5050);
DOT 1 (-1650 4600);
QUIT
